FILE_TYPE = MACRO_DRAWING;
SET COLOR_WIRE YELLOW;
SET COLOR_PROP MONO;
SET COLOR_DOT WHITE;
SET COLOR_ARC YELLOW;
SET COLOR_BODY GREEN;
SET COLOR_NOTE MONO;
SET PROP_DISPLAY VALUE;
SET PAGE_NUMBER P182;
FORCEADD OFFPAGE..5
(-7875 -175);
FORCEPROP 2 LAST $XR3 147 
J 0
(-8130 -211);
DISPLAY 0.638298 (-8130 -211);
PAINT MONO (-8130 -211);
FORCEPROP 2 LAST $XR2 119 
J 0
(-8370 -175);
DISPLAY 0.638298 (-8370 -175);
PAINT MONO (-8370 -175);
FORCEPROP 2 LAST $XR1 182 
J 0
(-8250 -175);
DISPLAY 0.638298 (-8250 -175);
PAINT MONO (-8250 -175);
FORCEPROP 2 LAST $XR0 133 
J 0
(-8130 -175);
DISPLAY 0.638298 (-8130 -175);
PAINT MONO (-8130 -175);
FORCEPROP 1 LAST OFFPAGE TRUE
J 0
(-7550 -300);
DISPLAY 0.872340 (-7550 -300);
PAINT GREEN (-7550 -300);
DISPLAY INVISIBLE (-7550 -300);
FORCEPROP 1 LAST COMMENT_BODY TRUE
J 0
(-7775 -250);
DISPLAY 0.872340 (-7775 -250);
PAINT GREEN (-7775 -250);
DISPLAY INVISIBLE (-7775 -250);
FORCEPROP 2 LAST CDS_LIB mstr_standard
J 0
(-7875 -175);
PAINT ORANGE (-7875 -175);
DISPLAY INVISIBLE (-7875 -175);
FORCEPROP 2 LAST PATH I1
J 0
(-8125 -125);
DISPLAY 1.021277 (-8125 -125);
PAINT ORANGE (-8125 -125);
DISPLAY INVISIBLE (-8125 -125);
FORCEADD RES..1
(-7000 350);
FORCEPROP 1 LAST PACK_TYPE 0402
J 0
(-6750 300);
DISPLAY 0.617021 (-6750 300);
PAINT SKYBLUE (-6750 300);
FORCEPROP 1 LAST MATERIAL EMPTY
J 0
(-6875 300);
DISPLAY 0.617021 (-6875 300);
PAINT RED (-6875 300);
FORCEPROP 1 LAST PART_NUMBER G21497-005
J 2
(-6650 350);
DISPLAY 0.617021 (-6650 350);
PAINT BLUE (-6650 350);
FORCEPROP 1 LASTPIN (-6900 350) $PN 2
J 0
(-6938 362);
DISPLAY 0.617021 (-6938 362);
PAINT ORANGE (-6938 362);
FORCEPROP 1 LAST TOLERANCE 5%
J 0
(-6950 300);
DISPLAY 0.617021 (-6950 300);
PAINT SKYBLUE (-6950 300);
FORCEPROP 1 LASTPIN (-7100 350) $PN 1
J 0
(-7088 362);
DISPLAY 0.617021 (-7088 362);
PAINT ORANGE (-7088 362);
FORCEPROP 1 LAST VALUE 0.0
J 2
(-7025 300);
DISPLAY 0.617021 (-7025 300);
PAINT SKYBLUE (-7025 300);
FORCEPROP 1 LAST WATTAGE 1/16W
J 2
(-7125 300);
DISPLAY 0.617021 (-7125 300);
PAINT SKYBLUE (-7125 300);
FORCEPROP 1 LAST LOCATION R1C11
J 2
(-7125 350);
DISPLAY 0.617021 (-7125 350);
PAINT AQUA (-7125 350);
FORCEPROP 2 LAST SEC_TYPE 0402
J 0
(-7050 550);
DISPLAY 1.021277 (-7050 550);
PAINT ORANGE (-7050 550);
DISPLAY INVISIBLE (-7050 550);
FORCEPROP 2 LAST SEC 1
J 0
(-7050 550);
DISPLAY 0.680851 (-7050 550);
PAINT MONO (-7050 550);
DISPLAY INVISIBLE (-7050 550);
FORCEPROP 2 LAST NO_XNET_CONNECTION 1
J 0
(-7050 550);
PAINT MONO (-7050 550);
DISPLAY INVISIBLE (-7050 550);
FORCEPROP 0 LAST ROOM IO_SLOT
J 0
(-6925 450);
DISPLAY 1.021277 (-6925 450);
PAINT ORANGE (-6925 450);
DISPLAY INVISIBLE (-6925 450);
FORCEPROP 2 LAST CDS_LIB mstr_discrete
J 0
(-7000 350);
PAINT ORANGE (-7000 350);
DISPLAY INVISIBLE (-7000 350);
FORCEPROP 2 LAST CDS_LOCATION R1C11
J 2
(-7125 350);
DISPLAY 0.617021 (-7125 350);
PAINT AQUA (-7125 350);
DISPLAY INVISIBLE (-7125 350);
FORCEPROP 0 LAST CDS_SEC 1
J 0
(-6650 400);
PAINT MONO (-6650 400);
DISPLAY INVISIBLE (-6650 400);
FORCEPROP 1 LAST PATH I10
J 0
(-7050 500);
DISPLAY 0.978723 (-7050 500);
PAINT WHITE (-7050 500);
DISPLAY INVISIBLE (-7050 500);
FORCEADD OFFPAGE..5
(-7100 1425);
FORCEPROP 2 LAST $XR1 147 
J 0
(-7475 1425);
DISPLAY 0.638298 (-7475 1425);
PAINT MONO (-7475 1425);
FORCEPROP 2 LAST $XR0 119 
J 0
(-7355 1425);
DISPLAY 0.638298 (-7355 1425);
PAINT MONO (-7355 1425);
FORCEPROP 1 LAST OFFPAGE TRUE
J 0
(-6775 1300);
DISPLAY 0.872340 (-6775 1300);
PAINT GREEN (-6775 1300);
DISPLAY INVISIBLE (-6775 1300);
FORCEPROP 1 LAST COMMENT_BODY TRUE
J 0
(-7000 1350);
DISPLAY 0.872340 (-7000 1350);
PAINT GREEN (-7000 1350);
DISPLAY INVISIBLE (-7000 1350);
FORCEPROP 2 LAST CDS_LIB mstr_standard
J 0
(-7100 1425);
PAINT MONO (-7100 1425);
DISPLAY INVISIBLE (-7100 1425);
FORCEPROP 2 LAST PATH I11
J 0
(-7375 1475);
DISPLAY 1.021277 (-7375 1475);
PAINT ORANGE (-7375 1475);
DISPLAY INVISIBLE (-7375 1475);
FORCEADD OFFPAGE..5
(-7975 3275);
FORCEPROP 2 LAST $XR0 66 
J 0
(-8199 3275);
DISPLAY 0.638298 (-8199 3275);
PAINT MONO (-8199 3275);
FORCEPROP 1 LAST OFFPAGE TRUE
J 0
(-7650 3150);
DISPLAY 0.872340 (-7650 3150);
PAINT GREEN (-7650 3150);
DISPLAY INVISIBLE (-7650 3150);
FORCEPROP 2 LAST CDS_LIB mstr_standard
J 0
(-7975 3275);
PAINT ORANGE (-7975 3275);
DISPLAY INVISIBLE (-7975 3275);
FORCEPROP 1 LAST COMMENT_BODY TRUE
J 0
(-7875 3200);
DISPLAY 0.872340 (-7875 3200);
PAINT GREEN (-7875 3200);
DISPLAY INVISIBLE (-7875 3200);
FORCEPROP 2 LAST PATH I12
J 0
(-8175 3325);
DISPLAY 1.021277 (-8175 3325);
PAINT ORANGE (-8175 3325);
DISPLAY INVISIBLE (-8175 3325);
FORCEADD OFFPAGE..5
(-7975 3400);
FORCEPROP 2 LAST $XR0 66 
J 0
(-8199 3400);
DISPLAY 0.638298 (-8199 3400);
PAINT MONO (-8199 3400);
FORCEPROP 1 LAST OFFPAGE TRUE
J 0
(-7650 3275);
DISPLAY 0.872340 (-7650 3275);
PAINT GREEN (-7650 3275);
DISPLAY INVISIBLE (-7650 3275);
FORCEPROP 2 LAST CDS_LIB mstr_standard
J 0
(-7975 3400);
PAINT ORANGE (-7975 3400);
DISPLAY INVISIBLE (-7975 3400);
FORCEPROP 1 LAST COMMENT_BODY TRUE
J 0
(-7875 3325);
DISPLAY 0.872340 (-7875 3325);
PAINT GREEN (-7875 3325);
DISPLAY INVISIBLE (-7875 3325);
FORCEPROP 2 LAST PATH I13
J 0
(-8175 3450);
DISPLAY 1.021277 (-8175 3450);
PAINT ORANGE (-8175 3450);
DISPLAY INVISIBLE (-8175 3450);
FORCEADD OFFPAGE..4
(-5975 -175);
FORCEPROP 2 LAST $XR0 181 
J 0
(-5789 -175);
DISPLAY 0.638298 (-5789 -175);
PAINT MONO (-5789 -175);
FORCEPROP 1 LAST OFFPAGE TRUE
J 0
(-5650 -300);
DISPLAY 0.872340 (-5650 -300);
PAINT GREEN (-5650 -300);
DISPLAY INVISIBLE (-5650 -300);
FORCEPROP 2 LAST CDS_LIB mstr_standard
J 0
(-5975 -175);
PAINT ORANGE (-5975 -175);
DISPLAY INVISIBLE (-5975 -175);
FORCEPROP 1 LAST COMMENT_BODY TRUE
J 0
(-6000 -275);
DISPLAY 0.872340 (-6000 -275);
PAINT GREEN (-6000 -275);
DISPLAY INVISIBLE (-6000 -275);
FORCEPROP 2 LAST PATH I14
J 0
(-5775 -125);
DISPLAY 1.021277 (-5775 -125);
PAINT ORANGE (-5775 -125);
DISPLAY INVISIBLE (-5775 -125);
FORCEADD OFFPAGE..2
(-5975 -25);
FORCEPROP 2 LAST $XR0 181 
J 0
(-5786 -25);
DISPLAY 0.638298 (-5786 -25);
PAINT MONO (-5786 -25);
FORCEPROP 2 LAST CDS_LIB mstr_standard
J 0
(-5975 -25);
PAINT ORANGE (-5975 -25);
DISPLAY INVISIBLE (-5975 -25);
FORCEPROP 1 LAST OFFPAGE TRUE
J 0
(-5650 -150);
DISPLAY 0.872340 (-5650 -150);
PAINT GREEN (-5650 -150);
DISPLAY INVISIBLE (-5650 -150);
FORCEPROP 1 LAST COMMENT_BODY TRUE
J 0
(-6020 -120);
DISPLAY 0.872340 (-6020 -120);
PAINT GREEN (-6020 -120);
DISPLAY INVISIBLE (-6020 -120);
FORCEPROP 2 LAST PATH I15
J 0
(-5775 25);
DISPLAY 1.021277 (-5775 25);
PAINT ORANGE (-5775 25);
DISPLAY INVISIBLE (-5775 25);
FORCEADD OFFPAGE..2
(-5975 100);
FORCEPROP 2 LAST $XR0 181 
J 0
(-5786 100);
DISPLAY 0.638298 (-5786 100);
PAINT MONO (-5786 100);
FORCEPROP 2 LAST CDS_LIB mstr_standard
J 0
(-5975 100);
PAINT ORANGE (-5975 100);
DISPLAY INVISIBLE (-5975 100);
FORCEPROP 1 LAST COMMENT_BODY TRUE
J 0
(-6020 5);
DISPLAY 0.872340 (-6020 5);
PAINT GREEN (-6020 5);
DISPLAY INVISIBLE (-6020 5);
FORCEPROP 1 LAST OFFPAGE TRUE
J 0
(-5650 -25);
DISPLAY 0.872340 (-5650 -25);
PAINT GREEN (-5650 -25);
DISPLAY INVISIBLE (-5650 -25);
FORCEPROP 2 LAST PATH I16
J 0
(-5775 150);
DISPLAY 1.021277 (-5775 150);
PAINT ORANGE (-5775 150);
DISPLAY INVISIBLE (-5775 150);
FORCEADD OFFPAGE..3
(-5975 225);
FORCEPROP 2 LAST $XR0 181 
J 0
(-5761 225);
DISPLAY 0.638298 (-5761 225);
PAINT MONO (-5761 225);
FORCEPROP 1 LAST OFFPAGE TRUE
J 0
(-5650 100);
DISPLAY 0.872340 (-5650 100);
PAINT GREEN (-5650 100);
DISPLAY INVISIBLE (-5650 100);
FORCEPROP 2 LAST CDS_LIB mstr_standard
J 0
(-5975 225);
PAINT ORANGE (-5975 225);
DISPLAY INVISIBLE (-5975 225);
FORCEPROP 1 LAST COMMENT_BODY TRUE
J 0
(-6025 125);
DISPLAY 0.872340 (-6025 125);
PAINT GREEN (-6025 125);
DISPLAY INVISIBLE (-6025 125);
FORCEPROP 2 LAST PATH I17
J 0
(-5750 275);
DISPLAY 1.021277 (-5750 275);
PAINT ORANGE (-5750 275);
DISPLAY INVISIBLE (-5750 275);
FORCEADD OFFPAGE..2
(-5975 350);
FORCEPROP 2 LAST $XR0 181 
J 0
(-5786 350);
DISPLAY 0.638298 (-5786 350);
PAINT MONO (-5786 350);
FORCEPROP 1 LAST OFFPAGE TRUE
J 0
(-5650 225);
DISPLAY 0.872340 (-5650 225);
PAINT GREEN (-5650 225);
DISPLAY INVISIBLE (-5650 225);
FORCEPROP 2 LAST CDS_LIB mstr_standard
J 0
(-5975 350);
PAINT ORANGE (-5975 350);
DISPLAY INVISIBLE (-5975 350);
FORCEPROP 1 LAST COMMENT_BODY TRUE
J 0
(-6020 255);
DISPLAY 0.872340 (-6020 255);
PAINT GREEN (-6020 255);
DISPLAY INVISIBLE (-6020 255);
FORCEPROP 2 LAST PATH I18
J 0
(-5775 400);
DISPLAY 1.021277 (-5775 400);
PAINT ORANGE (-5775 400);
DISPLAY INVISIBLE (-5775 400);
FORCEADD GND..1
(-5850 750);
FORCEPROP 3 LASTPIN (-5850 800) SIG_NAME GND\g
J 0
(-5840 810);
DISPLAY 0.659574 (-5840 810);
PAINT MONO (-5840 810);
DISPLAY INVISIBLE (-5840 810);
FORCEPROP 1 LAST SIZE 1B
J 0
(-5775 700);
DISPLAY 0.872340 (-5775 700);
PAINT GREEN (-5775 700);
DISPLAY INVISIBLE (-5775 700);
FORCEPROP 2 LAST CDS_LIB mstr_symbols
J 0
(-5850 750);
PAINT ORANGE (-5850 750);
DISPLAY INVISIBLE (-5850 750);
FORCEPROP 1 LAST BODY_TYPE PLUMBING
J 0
(-5895 707);
DISPLAY 0.340426 (-5895 707);
PAINT GREEN (-5895 707);
DISPLAY INVISIBLE (-5895 707);
FORCEPROP 2 LAST ROOM P2V5_LAN_AUX_VR
J 0
(-6150 825);
DISPLAY 0.617021 (-6150 825);
PAINT ORANGE (-6150 825);
DISPLAY INVISIBLE (-6150 825);
FORCEPROP 1 LAST HDL_POWER GND
J 0
(-5850 900);
DISPLAY 0.872340 (-5850 900);
PAINT GREEN (-5850 900);
DISPLAY INVISIBLE (-5850 900);
FORCEPROP 2 LAST BOM_COST NT_BASE_VRD
J 0
(-6150 825);
DISPLAY 0.617021 (-6150 825);
PAINT ORANGE (-6150 825);
DISPLAY INVISIBLE (-6150 825);
FORCEPROP 1 LAST VOLTAGE 0
J 0
(-5850 750);
PAINT SKYBLUE (-5850 750);
DISPLAY INVISIBLE (-5850 750);
FORCEPROP 1 LAST PATH I19
J 0
(-5775 750);
DISPLAY 0.872340 (-5775 750);
PAINT AQUA (-5775 750);
DISPLAY INVISIBLE (-5775 750);
FORCEADD OFFPAGE..1
(-7875 -25);
FORCEPROP 2 LAST $XR3 119 
J 0
(-8127 -61);
DISPLAY 0.638298 (-8127 -61);
PAINT MONO (-8127 -61);
FORCEPROP 2 LAST $XR2 146 
J 0
(-8367 -25);
DISPLAY 0.638298 (-8367 -25);
PAINT MONO (-8367 -25);
FORCEPROP 2 LAST $XR1 133 
J 0
(-8247 -25);
DISPLAY 0.638298 (-8247 -25);
PAINT MONO (-8247 -25);
FORCEPROP 2 LAST $XR0 120 
J 0
(-8127 -25);
DISPLAY 0.638298 (-8127 -25);
PAINT MONO (-8127 -25);
FORCEPROP 1 LAST OFFPAGE TRUE
J 0
(-7550 -150);
DISPLAY 0.872340 (-7550 -150);
PAINT GREEN (-7550 -150);
DISPLAY INVISIBLE (-7550 -150);
FORCEPROP 2 LAST CDS_LIB mstr_standard
J 0
(-7875 -25);
PAINT ORANGE (-7875 -25);
DISPLAY INVISIBLE (-7875 -25);
FORCEPROP 1 LAST COMMENT_BODY TRUE
J 0
(-7750 -125);
DISPLAY 0.872340 (-7750 -125);
PAINT GREEN (-7750 -125);
DISPLAY INVISIBLE (-7750 -125);
FORCEPROP 2 LAST PATH I2
J 0
(-8125 25);
DISPLAY 1.021277 (-8125 25);
PAINT ORANGE (-8125 25);
DISPLAY INVISIBLE (-8125 25);
FORCEADD TAP..1
R 2
(-6350 1975);
FORCEPROP 3 LASTPIN (-6300 1975) SIG_NAME P3E_CPU1_PE3_MP_RXN<14>
J 0
(-6290 1985);
DISPLAY 0.659574 (-6290 1985);
PAINT MONO (-6290 1985);
DISPLAY INVISIBLE (-6290 1985);
FORCEPROP 1 LASTPIN (-6300 1975) BN 14
J 2
(-6288 1983);
DISPLAY 0.617021 (-6288 1983);
PAINT GREEN (-6288 1983);
FORCEPROP 1 LAST BODY_TYPE PLUMBING
J 2
(-6350 2025);
DISPLAY 1.446809 (-6350 2025);
PAINT GREEN (-6350 2025);
DISPLAY INVISIBLE (-6350 2025);
FORCEPROP 2 LAST CDS_LIB mstr_standard
J 0
(-6350 1975);
PAINT MONO (-6350 1975);
DISPLAY INVISIBLE (-6350 1975);
FORCEPROP 1 LAST HDL_TAP TRUE
J 2
(-6675 1850);
DISPLAY 1.446809 (-6675 1850);
PAINT GREEN (-6675 1850);
DISPLAY INVISIBLE (-6675 1850);
FORCEPROP 1 LAST PATH I20
J 2
(-6348 1975);
DISPLAY 0.872340 (-6348 1975);
PAINT GREEN (-6348 1975);
DISPLAY INVISIBLE (-6348 1975);
FORCEADD TAP..1
R 2
(-6350 1875);
FORCEPROP 3 LASTPIN (-6300 1875) SIG_NAME P3E_CPU1_PE3_MP_RXN<15>
J 0
(-6290 1885);
DISPLAY 0.659574 (-6290 1885);
PAINT MONO (-6290 1885);
DISPLAY INVISIBLE (-6290 1885);
FORCEPROP 1 LASTPIN (-6300 1875) BN 15
J 2
(-6288 1883);
DISPLAY 0.617021 (-6288 1883);
PAINT GREEN (-6288 1883);
FORCEPROP 2 LAST CDS_LIB mstr_standard
J 0
(-6350 1875);
PAINT MONO (-6350 1875);
DISPLAY INVISIBLE (-6350 1875);
FORCEPROP 1 LAST BODY_TYPE PLUMBING
J 2
(-6350 1925);
DISPLAY 1.446809 (-6350 1925);
PAINT GREEN (-6350 1925);
DISPLAY INVISIBLE (-6350 1925);
FORCEPROP 1 LAST HDL_TAP TRUE
J 2
(-6675 1750);
DISPLAY 1.446809 (-6675 1750);
PAINT GREEN (-6675 1750);
DISPLAY INVISIBLE (-6675 1750);
FORCEPROP 1 LAST PATH I21
J 2
(-6348 1875);
DISPLAY 0.872340 (-6348 1875);
PAINT GREEN (-6348 1875);
DISPLAY INVISIBLE (-6348 1875);
FORCEADD TAP..1
R 2
(-6350 2175);
FORCEPROP 3 LASTPIN (-6300 2175) SIG_NAME P3E_CPU1_PE3_MP_RXN<13>
J 0
(-6290 2185);
DISPLAY 0.659574 (-6290 2185);
PAINT MONO (-6290 2185);
DISPLAY INVISIBLE (-6290 2185);
FORCEPROP 1 LASTPIN (-6300 2175) BN 13
J 2
(-6288 2183);
DISPLAY 0.617021 (-6288 2183);
PAINT GREEN (-6288 2183);
FORCEPROP 2 LAST CDS_LIB mstr_standard
J 0
(-6350 2175);
PAINT ORANGE (-6350 2175);
DISPLAY INVISIBLE (-6350 2175);
FORCEPROP 1 LAST BODY_TYPE PLUMBING
J 2
(-6350 2225);
DISPLAY 1.446809 (-6350 2225);
PAINT GREEN (-6350 2225);
DISPLAY INVISIBLE (-6350 2225);
FORCEPROP 1 LAST HDL_TAP TRUE
J 2
(-6675 2050);
DISPLAY 1.446809 (-6675 2050);
PAINT GREEN (-6675 2050);
DISPLAY INVISIBLE (-6675 2050);
FORCEPROP 1 LAST PATH I22
J 2
(-6348 2175);
DISPLAY 0.872340 (-6348 2175);
PAINT GREEN (-6348 2175);
DISPLAY INVISIBLE (-6348 2175);
FORCEADD TAP..1
R 2
(-6350 2375);
FORCEPROP 3 LASTPIN (-6300 2375) SIG_NAME P3E_CPU1_PE3_MP_RXN<12>
J 0
(-6290 2385);
DISPLAY 0.659574 (-6290 2385);
PAINT MONO (-6290 2385);
DISPLAY INVISIBLE (-6290 2385);
FORCEPROP 1 LASTPIN (-6300 2375) BN 12
J 2
(-6288 2383);
DISPLAY 0.617021 (-6288 2383);
PAINT GREEN (-6288 2383);
FORCEPROP 2 LAST CDS_LIB mstr_standard
J 0
(-6350 2375);
PAINT MONO (-6350 2375);
DISPLAY INVISIBLE (-6350 2375);
FORCEPROP 1 LAST BODY_TYPE PLUMBING
J 2
(-6350 2425);
DISPLAY 1.446809 (-6350 2425);
PAINT GREEN (-6350 2425);
DISPLAY INVISIBLE (-6350 2425);
FORCEPROP 1 LAST HDL_TAP TRUE
J 2
(-6675 2250);
DISPLAY 1.446809 (-6675 2250);
PAINT GREEN (-6675 2250);
DISPLAY INVISIBLE (-6675 2250);
FORCEPROP 1 LAST PATH I23
J 2
(-6348 2375);
DISPLAY 0.872340 (-6348 2375);
PAINT GREEN (-6348 2375);
DISPLAY INVISIBLE (-6348 2375);
FORCEADD TAP..1
R 2
(-6100 2025);
FORCEPROP 3 LASTPIN (-6050 2025) SIG_NAME P3E_CPU1_PE3_MP_RXP<14>
J 0
(-6040 2035);
DISPLAY 0.659574 (-6040 2035);
PAINT MONO (-6040 2035);
DISPLAY INVISIBLE (-6040 2035);
FORCEPROP 1 LASTPIN (-6050 2025) BN 14
J 2
(-6038 2033);
DISPLAY 0.617021 (-6038 2033);
PAINT GREEN (-6038 2033);
FORCEPROP 1 LAST BODY_TYPE PLUMBING
J 2
(-6100 2075);
DISPLAY 1.446809 (-6100 2075);
PAINT GREEN (-6100 2075);
DISPLAY INVISIBLE (-6100 2075);
FORCEPROP 2 LAST CDS_LIB mstr_standard
J 0
(-6100 2025);
PAINT MONO (-6100 2025);
DISPLAY INVISIBLE (-6100 2025);
FORCEPROP 1 LAST HDL_TAP TRUE
J 2
(-6425 1900);
DISPLAY 1.446809 (-6425 1900);
PAINT GREEN (-6425 1900);
DISPLAY INVISIBLE (-6425 1900);
FORCEPROP 1 LAST PATH I24
J 2
(-6098 2025);
DISPLAY 0.872340 (-6098 2025);
PAINT GREEN (-6098 2025);
DISPLAY INVISIBLE (-6098 2025);
FORCEADD TAP..1
R 2
(-6100 1825);
FORCEPROP 3 LASTPIN (-6050 1825) SIG_NAME P3E_CPU1_PE3_MP_RXP<15>
J 0
(-6040 1835);
DISPLAY 0.659574 (-6040 1835);
PAINT MONO (-6040 1835);
DISPLAY INVISIBLE (-6040 1835);
FORCEPROP 1 LASTPIN (-6050 1825) BN 15
J 2
(-6038 1833);
DISPLAY 0.617021 (-6038 1833);
PAINT GREEN (-6038 1833);
FORCEPROP 1 LAST BODY_TYPE PLUMBING
J 2
(-6100 1875);
DISPLAY 1.446809 (-6100 1875);
PAINT GREEN (-6100 1875);
DISPLAY INVISIBLE (-6100 1875);
FORCEPROP 2 LAST CDS_LIB mstr_standard
J 0
(-6100 1825);
PAINT MONO (-6100 1825);
DISPLAY INVISIBLE (-6100 1825);
FORCEPROP 1 LAST HDL_TAP TRUE
J 2
(-6425 1700);
DISPLAY 1.446809 (-6425 1700);
PAINT GREEN (-6425 1700);
DISPLAY INVISIBLE (-6425 1700);
FORCEPROP 1 LAST PATH I25
J 2
(-6098 1825);
DISPLAY 0.872340 (-6098 1825);
PAINT GREEN (-6098 1825);
DISPLAY INVISIBLE (-6098 1825);
FORCEADD TAP..1
R 2
(-6100 2225);
FORCEPROP 3 LASTPIN (-6050 2225) SIG_NAME P3E_CPU1_PE3_MP_RXP<13>
J 0
(-6040 2235);
DISPLAY 0.659574 (-6040 2235);
PAINT MONO (-6040 2235);
DISPLAY INVISIBLE (-6040 2235);
FORCEPROP 1 LASTPIN (-6050 2225) BN 13
J 2
(-6038 2233);
DISPLAY 0.617021 (-6038 2233);
PAINT GREEN (-6038 2233);
FORCEPROP 1 LAST BODY_TYPE PLUMBING
J 2
(-6100 2275);
DISPLAY 1.446809 (-6100 2275);
PAINT GREEN (-6100 2275);
DISPLAY INVISIBLE (-6100 2275);
FORCEPROP 2 LAST CDS_LIB mstr_standard
J 0
(-6100 2225);
PAINT ORANGE (-6100 2225);
DISPLAY INVISIBLE (-6100 2225);
FORCEPROP 1 LAST HDL_TAP TRUE
J 2
(-6425 2100);
DISPLAY 1.446809 (-6425 2100);
PAINT GREEN (-6425 2100);
DISPLAY INVISIBLE (-6425 2100);
FORCEPROP 1 LAST PATH I26
J 2
(-6098 2225);
DISPLAY 0.872340 (-6098 2225);
PAINT GREEN (-6098 2225);
DISPLAY INVISIBLE (-6098 2225);
FORCEADD TAP..1
R 2
(-6100 2325);
FORCEPROP 3 LASTPIN (-6050 2325) SIG_NAME P3E_CPU1_PE3_MP_RXP<12>
J 0
(-6040 2335);
DISPLAY 0.659574 (-6040 2335);
PAINT MONO (-6040 2335);
DISPLAY INVISIBLE (-6040 2335);
FORCEPROP 1 LASTPIN (-6050 2325) BN 12
J 2
(-6038 2333);
DISPLAY 0.617021 (-6038 2333);
PAINT GREEN (-6038 2333);
FORCEPROP 1 LAST BODY_TYPE PLUMBING
J 2
(-6100 2375);
DISPLAY 1.446809 (-6100 2375);
PAINT GREEN (-6100 2375);
DISPLAY INVISIBLE (-6100 2375);
FORCEPROP 2 LAST CDS_LIB mstr_standard
J 0
(-6100 2325);
PAINT MONO (-6100 2325);
DISPLAY INVISIBLE (-6100 2325);
FORCEPROP 1 LAST HDL_TAP TRUE
J 2
(-6425 2200);
DISPLAY 1.446809 (-6425 2200);
PAINT GREEN (-6425 2200);
DISPLAY INVISIBLE (-6425 2200);
FORCEPROP 1 LAST PATH I27
J 2
(-6098 2325);
DISPLAY 0.872340 (-6098 2325);
PAINT GREEN (-6098 2325);
DISPLAY INVISIBLE (-6098 2325);
FORCEADD TAP..1
R 2
(-6100 2475);
FORCEPROP 3 LASTPIN (-6050 2475) SIG_NAME P3E_CPU1_PE3_MP_RXP<11>
J 0
(-6040 2485);
DISPLAY 0.659574 (-6040 2485);
PAINT MONO (-6040 2485);
DISPLAY INVISIBLE (-6040 2485);
FORCEPROP 1 LASTPIN (-6050 2475) BN 11
J 2
(-6038 2483);
DISPLAY 0.617021 (-6038 2483);
PAINT GREEN (-6038 2483);
FORCEPROP 1 LAST BODY_TYPE PLUMBING
J 2
(-6100 2525);
DISPLAY 1.446809 (-6100 2525);
PAINT GREEN (-6100 2525);
DISPLAY INVISIBLE (-6100 2525);
FORCEPROP 2 LAST CDS_LIB mstr_standard
J 0
(-6100 2475);
PAINT MONO (-6100 2475);
DISPLAY INVISIBLE (-6100 2475);
FORCEPROP 1 LAST HDL_TAP TRUE
J 2
(-6425 2350);
DISPLAY 1.446809 (-6425 2350);
PAINT GREEN (-6425 2350);
DISPLAY INVISIBLE (-6425 2350);
FORCEPROP 1 LAST PATH I28
J 2
(-6098 2475);
DISPLAY 0.872340 (-6098 2475);
PAINT GREEN (-6098 2475);
DISPLAY INVISIBLE (-6098 2475);
FORCEADD TAP..1
R 2
(-6350 2725);
FORCEPROP 3 LASTPIN (-6300 2725) SIG_NAME P3E_CPU1_PE3_MP_RXN<10>
J 0
(-6290 2735);
DISPLAY 0.659574 (-6290 2735);
PAINT MONO (-6290 2735);
DISPLAY INVISIBLE (-6290 2735);
FORCEPROP 1 LASTPIN (-6300 2725) BN 10
J 2
(-6288 2733);
DISPLAY 0.617021 (-6288 2733);
PAINT GREEN (-6288 2733);
FORCEPROP 1 LAST BODY_TYPE PLUMBING
J 2
(-6350 2775);
DISPLAY 1.446809 (-6350 2775);
PAINT GREEN (-6350 2775);
DISPLAY INVISIBLE (-6350 2775);
FORCEPROP 2 LAST CDS_LIB mstr_standard
J 0
(-6350 2725);
PAINT ORANGE (-6350 2725);
DISPLAY INVISIBLE (-6350 2725);
FORCEPROP 1 LAST HDL_TAP TRUE
J 2
(-6675 2600);
DISPLAY 1.446809 (-6675 2600);
PAINT GREEN (-6675 2600);
DISPLAY INVISIBLE (-6675 2600);
FORCEPROP 1 LAST PATH I29
J 2
(-6348 2725);
DISPLAY 0.872340 (-6348 2725);
PAINT GREEN (-6348 2725);
DISPLAY INVISIBLE (-6348 2725);
FORCEADD OFFPAGE..1
(-7875 100);
FORCEPROP 2 LAST $XR3 182 
J 0
(-8127 64);
DISPLAY 0.638298 (-8127 64);
PAINT MONO (-8127 64);
FORCEPROP 2 LAST $XR2 145 
J 0
(-8367 100);
DISPLAY 0.638298 (-8367 100);
PAINT MONO (-8367 100);
FORCEPROP 2 LAST $XR1 133 
J 0
(-8247 100);
DISPLAY 0.638298 (-8247 100);
PAINT MONO (-8247 100);
FORCEPROP 2 LAST $XR0 120 
J 0
(-8127 100);
DISPLAY 0.638298 (-8127 100);
PAINT MONO (-8127 100);
FORCEPROP 1 LAST OFFPAGE TRUE
J 0
(-7550 -25);
DISPLAY 0.872340 (-7550 -25);
PAINT GREEN (-7550 -25);
DISPLAY INVISIBLE (-7550 -25);
FORCEPROP 1 LAST COMMENT_BODY TRUE
J 0
(-7750 0);
DISPLAY 0.872340 (-7750 0);
PAINT GREEN (-7750 0);
DISPLAY INVISIBLE (-7750 0);
FORCEPROP 2 LAST CDS_LIB mstr_standard
J 0
(-7875 100);
PAINT ORANGE (-7875 100);
DISPLAY INVISIBLE (-7875 100);
FORCEPROP 2 LAST PATH I3
J 0
(-8125 150);
DISPLAY 1.021277 (-8125 150);
PAINT ORANGE (-8125 150);
DISPLAY INVISIBLE (-8125 150);
FORCEADD TAP..1
R 2
(-6350 2925);
FORCEPROP 3 LASTPIN (-6300 2925) SIG_NAME P3E_CPU1_PE3_MP_RXN<9>
J 0
(-6290 2935);
DISPLAY 0.659574 (-6290 2935);
PAINT MONO (-6290 2935);
DISPLAY INVISIBLE (-6290 2935);
FORCEPROP 1 LASTPIN (-6300 2925) BN 9
J 2
(-6288 2933);
DISPLAY 0.617021 (-6288 2933);
PAINT GREEN (-6288 2933);
FORCEPROP 2 LAST CDS_LIB mstr_standard
J 0
(-6350 2925);
PAINT MONO (-6350 2925);
DISPLAY INVISIBLE (-6350 2925);
FORCEPROP 1 LAST BODY_TYPE PLUMBING
J 2
(-6350 2975);
DISPLAY 1.446809 (-6350 2975);
PAINT GREEN (-6350 2975);
DISPLAY INVISIBLE (-6350 2975);
FORCEPROP 1 LAST HDL_TAP TRUE
J 2
(-6675 2800);
DISPLAY 1.446809 (-6675 2800);
PAINT GREEN (-6675 2800);
DISPLAY INVISIBLE (-6675 2800);
FORCEPROP 1 LAST PATH I30
J 2
(-6348 2925);
DISPLAY 0.872340 (-6348 2925);
PAINT GREEN (-6348 2925);
DISPLAY INVISIBLE (-6348 2925);
FORCEADD TAP..1
R 2
(-6350 3075);
FORCEPROP 3 LASTPIN (-6300 3075) SIG_NAME P3E_CPU1_PE3_MP_RXN<8>
J 0
(-6290 3085);
DISPLAY 0.659574 (-6290 3085);
PAINT MONO (-6290 3085);
DISPLAY INVISIBLE (-6290 3085);
FORCEPROP 1 LASTPIN (-6300 3075) BN 8
J 2
(-6288 3083);
DISPLAY 0.617021 (-6288 3083);
PAINT GREEN (-6288 3083);
FORCEPROP 2 LAST CDS_LIB mstr_standard
J 0
(-6350 3075);
PAINT MONO (-6350 3075);
DISPLAY INVISIBLE (-6350 3075);
FORCEPROP 1 LAST BODY_TYPE PLUMBING
J 2
(-6350 3125);
DISPLAY 1.446809 (-6350 3125);
PAINT GREEN (-6350 3125);
DISPLAY INVISIBLE (-6350 3125);
FORCEPROP 1 LAST HDL_TAP TRUE
J 2
(-6675 2950);
DISPLAY 1.446809 (-6675 2950);
PAINT GREEN (-6675 2950);
DISPLAY INVISIBLE (-6675 2950);
FORCEPROP 1 LAST PATH I31
J 2
(-6348 3075);
DISPLAY 0.872340 (-6348 3075);
PAINT GREEN (-6348 3075);
DISPLAY INVISIBLE (-6348 3075);
FORCEADD TAP..1
R 2
(-6100 2775);
FORCEPROP 3 LASTPIN (-6050 2775) SIG_NAME P3E_CPU1_PE3_MP_RXP<10>
J 0
(-6040 2785);
DISPLAY 0.659574 (-6040 2785);
PAINT MONO (-6040 2785);
DISPLAY INVISIBLE (-6040 2785);
FORCEPROP 1 LASTPIN (-6050 2775) BN 10
J 2
(-6038 2783);
DISPLAY 0.617021 (-6038 2783);
PAINT GREEN (-6038 2783);
FORCEPROP 1 LAST BODY_TYPE PLUMBING
J 2
(-6100 2825);
DISPLAY 1.446809 (-6100 2825);
PAINT GREEN (-6100 2825);
DISPLAY INVISIBLE (-6100 2825);
FORCEPROP 2 LAST CDS_LIB mstr_standard
J 0
(-6100 2775);
PAINT ORANGE (-6100 2775);
DISPLAY INVISIBLE (-6100 2775);
FORCEPROP 1 LAST HDL_TAP TRUE
J 2
(-6425 2650);
DISPLAY 1.446809 (-6425 2650);
PAINT GREEN (-6425 2650);
DISPLAY INVISIBLE (-6425 2650);
FORCEPROP 1 LAST PATH I32
J 2
(-6098 2775);
DISPLAY 0.872340 (-6098 2775);
PAINT GREEN (-6098 2775);
DISPLAY INVISIBLE (-6098 2775);
FORCEADD TAP..1
R 2
(-6100 2875);
FORCEPROP 3 LASTPIN (-6050 2875) SIG_NAME P3E_CPU1_PE3_MP_RXP<9>
J 0
(-6040 2885);
DISPLAY 0.659574 (-6040 2885);
PAINT MONO (-6040 2885);
DISPLAY INVISIBLE (-6040 2885);
FORCEPROP 1 LASTPIN (-6050 2875) BN 9
J 2
(-6038 2883);
DISPLAY 0.617021 (-6038 2883);
PAINT GREEN (-6038 2883);
FORCEPROP 1 LAST BODY_TYPE PLUMBING
J 2
(-6100 2925);
DISPLAY 1.446809 (-6100 2925);
PAINT GREEN (-6100 2925);
DISPLAY INVISIBLE (-6100 2925);
FORCEPROP 2 LAST CDS_LIB mstr_standard
J 0
(-6100 2875);
PAINT MONO (-6100 2875);
DISPLAY INVISIBLE (-6100 2875);
FORCEPROP 1 LAST HDL_TAP TRUE
J 2
(-6425 2750);
DISPLAY 1.446809 (-6425 2750);
PAINT GREEN (-6425 2750);
DISPLAY INVISIBLE (-6425 2750);
FORCEPROP 1 LAST PATH I33
J 2
(-6098 2875);
DISPLAY 0.872340 (-6098 2875);
PAINT GREEN (-6098 2875);
DISPLAY INVISIBLE (-6098 2875);
FORCEADD TAP..1
R 2
(-6100 3025);
FORCEPROP 3 LASTPIN (-6050 3025) SIG_NAME P3E_CPU1_PE3_MP_RXP<8>
J 0
(-6040 3035);
DISPLAY 0.659574 (-6040 3035);
PAINT MONO (-6040 3035);
DISPLAY INVISIBLE (-6040 3035);
FORCEPROP 1 LASTPIN (-6050 3025) BN 8
J 2
(-6038 3033);
DISPLAY 0.617021 (-6038 3033);
PAINT GREEN (-6038 3033);
FORCEPROP 1 LAST BODY_TYPE PLUMBING
J 2
(-6100 3075);
DISPLAY 1.446809 (-6100 3075);
PAINT GREEN (-6100 3075);
DISPLAY INVISIBLE (-6100 3075);
FORCEPROP 2 LAST CDS_LIB mstr_standard
J 0
(-6100 3025);
PAINT MONO (-6100 3025);
DISPLAY INVISIBLE (-6100 3025);
FORCEPROP 1 LAST HDL_TAP TRUE
J 2
(-6425 2900);
DISPLAY 1.446809 (-6425 2900);
PAINT GREEN (-6425 2900);
DISPLAY INVISIBLE (-6425 2900);
FORCEPROP 1 LAST PATH I34
J 2
(-6098 3025);
DISPLAY 0.872340 (-6098 3025);
PAINT GREEN (-6098 3025);
DISPLAY INVISIBLE (-6098 3025);
FORCEADD GND..1
(-4200 700);
FORCEPROP 3 LASTPIN (-4200 750) SIG_NAME GND\g
J 0
(-4190 760);
DISPLAY 0.659574 (-4190 760);
PAINT MONO (-4190 760);
DISPLAY INVISIBLE (-4190 760);
FORCEPROP 1 LAST VOLTAGE 0
J 0
(-4200 700);
PAINT SKYBLUE (-4200 700);
DISPLAY INVISIBLE (-4200 700);
FORCEPROP 2 LAST BOM_COST NT_BASE_VRD
J 0
(-4500 775);
DISPLAY 0.617021 (-4500 775);
PAINT ORANGE (-4500 775);
DISPLAY INVISIBLE (-4500 775);
FORCEPROP 2 LAST CDS_LIB mstr_symbols
J 0
(-4200 700);
PAINT MONO (-4200 700);
DISPLAY INVISIBLE (-4200 700);
FORCEPROP 1 LAST SIZE 1B
J 0
(-4125 650);
DISPLAY 0.872340 (-4125 650);
PAINT GREEN (-4125 650);
DISPLAY INVISIBLE (-4125 650);
FORCEPROP 1 LAST BODY_TYPE PLUMBING
J 0
(-4245 657);
DISPLAY 0.340426 (-4245 657);
PAINT GREEN (-4245 657);
DISPLAY INVISIBLE (-4245 657);
FORCEPROP 2 LAST ROOM P2V5_LAN_AUX_VR
J 0
(-4500 775);
DISPLAY 0.617021 (-4500 775);
PAINT ORANGE (-4500 775);
DISPLAY INVISIBLE (-4500 775);
FORCEPROP 1 LAST HDL_POWER GND
J 0
(-4200 850);
DISPLAY 0.872340 (-4200 850);
PAINT GREEN (-4200 850);
DISPLAY INVISIBLE (-4200 850);
FORCEPROP 1 LAST PATH I35
J 0
(-4125 700);
DISPLAY 0.872340 (-4125 700);
PAINT AQUA (-4125 700);
DISPLAY INVISIBLE (-4125 700);
FORCEADD CAP..2
(-3400 1125);
FORCEPROP 1 LAST TOLERANCE 10%
J 2
(-2975 1100);
DISPLAY 0.617021 (-2975 1100);
PAINT SKYBLUE (-2975 1100);
FORCEPROP 1 LAST MATERIAL X7R
J 0
(-3175 1100);
DISPLAY 0.617021 (-3175 1100);
PAINT SKYBLUE (-3175 1100);
FORCEPROP 1 LAST PART_NUMBER A36096-155
J 1
(-3175 1200);
DISPLAY 0.617021 (-3175 1200);
PAINT BLUE (-3175 1200);
FORCEPROP 1 LAST PACK_TYPE 0402
J 1
(-2875 1100);
DISPLAY 0.617021 (-2875 1100);
PAINT SKYBLUE (-2875 1100);
FORCEPROP 1 LAST VOLTAGE 16V
J 0
(-3300 1100);
DISPLAY 0.617021 (-3300 1100);
PAINT SKYBLUE (-3300 1100);
FORCEPROP 1 LAST LOCATION C9N2
J 1
(-3400 1200);
DISPLAY 0.617021 (-3400 1200);
PAINT AQUA (-3400 1200);
FORCEPROP 1 LASTPIN (-3300 1125) $PN 2
J 0
(-3315 1140);
DISPLAY 0.617021 (-3315 1140);
PAINT ORANGE (-3315 1140);
FORCEPROP 1 LASTPIN (-3500 1125) $PN 1
J 0
(-3510 1140);
DISPLAY 0.617021 (-3510 1140);
PAINT ORANGE (-3510 1140);
FORCEPROP 1 LAST VALUE 0.22UF
J 2
(-3450 1075);
DISPLAY 0.617021 (-3450 1075);
PAINT SKYBLUE (-3450 1075);
FORCEPROP 2 LAST SEC_TYPE 0402
J 0
(-3400 1375);
DISPLAY 1.021277 (-3400 1375);
PAINT ORANGE (-3400 1375);
DISPLAY INVISIBLE (-3400 1375);
FORCEPROP 2 LAST SEC 1
J 0
(-3400 1375);
DISPLAY 0.680851 (-3400 1375);
PAINT MONO (-3400 1375);
DISPLAY INVISIBLE (-3400 1375);
FORCEPROP 0 LAST BOM_COST IO_SLOT
J 0
(-3400 1275);
DISPLAY 1.021277 (-3400 1275);
PAINT ORANGE (-3400 1275);
DISPLAY INVISIBLE (-3400 1275);
FORCEPROP 0 LAST ROOM IO_SLOT
J 0
(-3400 1325);
DISPLAY 1.021277 (-3400 1325);
PAINT ORANGE (-3400 1325);
DISPLAY INVISIBLE (-3400 1325);
FORCEPROP 2 LAST CDS_LIB mstr_discrete
J 0
(-3400 1125);
PAINT ORANGE (-3400 1125);
DISPLAY INVISIBLE (-3400 1125);
FORCEPROP 2 LAST CDS_LOCATION C9N2
J 1
(-3400 1200);
DISPLAY 0.617021 (-3400 1200);
PAINT AQUA (-3400 1200);
DISPLAY INVISIBLE (-3400 1200);
FORCEPROP 0 LAST CDS_SEC 1
J 0
(-3175 1250);
PAINT MONO (-3175 1250);
DISPLAY INVISIBLE (-3175 1250);
FORCEPROP 1 LAST PATH I36
J 0
(-3400 1325);
DISPLAY 0.978723 (-3400 1325);
PAINT WHITE (-3400 1325);
DISPLAY INVISIBLE (-3400 1325);
FORCEADD CAP..2
(-3400 1275);
FORCEPROP 1 LAST PART_NUMBER A36096-155
J 1
(-3175 1350);
DISPLAY 0.617021 (-3175 1350);
PAINT BLUE (-3175 1350);
FORCEPROP 1 LAST LOCATION C9N12
J 1
(-3400 1350);
DISPLAY 0.617021 (-3400 1350);
PAINT AQUA (-3400 1350);
FORCEPROP 1 LASTPIN (-3300 1275) $PN 2
J 0
(-3315 1290);
DISPLAY 0.617021 (-3315 1290);
PAINT ORANGE (-3315 1290);
FORCEPROP 1 LAST PACK_TYPE 0402
J 1
(-2875 1250);
DISPLAY 0.617021 (-2875 1250);
PAINT SKYBLUE (-2875 1250);
FORCEPROP 1 LAST TOLERANCE 10%
J 2
(-2975 1250);
DISPLAY 0.617021 (-2975 1250);
PAINT SKYBLUE (-2975 1250);
FORCEPROP 1 LAST MATERIAL X7R
J 0
(-3175 1250);
DISPLAY 0.617021 (-3175 1250);
PAINT SKYBLUE (-3175 1250);
FORCEPROP 1 LAST VOLTAGE 16V
J 0
(-3300 1250);
DISPLAY 0.617021 (-3300 1250);
PAINT SKYBLUE (-3300 1250);
FORCEPROP 1 LASTPIN (-3500 1275) $PN 1
J 0
(-3510 1290);
DISPLAY 0.617021 (-3510 1290);
PAINT ORANGE (-3510 1290);
FORCEPROP 1 LAST VALUE 0.22UF
J 2
(-3450 1225);
DISPLAY 0.617021 (-3450 1225);
PAINT SKYBLUE (-3450 1225);
FORCEPROP 2 LAST SEC 1
J 0
(-3400 1525);
DISPLAY 0.680851 (-3400 1525);
PAINT MONO (-3400 1525);
DISPLAY INVISIBLE (-3400 1525);
FORCEPROP 2 LAST SEC_TYPE 0402
J 0
(-3400 1525);
DISPLAY 1.021277 (-3400 1525);
PAINT ORANGE (-3400 1525);
DISPLAY INVISIBLE (-3400 1525);
FORCEPROP 0 LAST BOM_COST IO_SLOT
J 0
(-3400 1425);
DISPLAY 1.021277 (-3400 1425);
PAINT ORANGE (-3400 1425);
DISPLAY INVISIBLE (-3400 1425);
FORCEPROP 0 LAST ROOM IO_SLOT
J 0
(-3400 1475);
DISPLAY 1.021277 (-3400 1475);
PAINT ORANGE (-3400 1475);
DISPLAY INVISIBLE (-3400 1475);
FORCEPROP 2 LAST CDS_LOCATION C9N12
J 1
(-3400 1350);
DISPLAY 0.617021 (-3400 1350);
PAINT AQUA (-3400 1350);
DISPLAY INVISIBLE (-3400 1350);
FORCEPROP 2 LAST CDS_LIB mstr_discrete
J 0
(-3400 1275);
PAINT ORANGE (-3400 1275);
DISPLAY INVISIBLE (-3400 1275);
FORCEPROP 0 LAST CDS_SEC 1
J 0
(-3175 1400);
PAINT MONO (-3175 1400);
DISPLAY INVISIBLE (-3175 1400);
FORCEPROP 1 LAST PATH I37
J 0
(-3400 1475);
DISPLAY 0.978723 (-3400 1475);
PAINT WHITE (-3400 1475);
DISPLAY INVISIBLE (-3400 1475);
FORCEADD CAP..2
(-3400 1425);
FORCEPROP 1 LAST PART_NUMBER A36096-155
J 1
(-3175 1500);
DISPLAY 0.617021 (-3175 1500);
PAINT BLUE (-3175 1500);
FORCEPROP 1 LAST LOCATION C9N17
J 1
(-3400 1500);
DISPLAY 0.617021 (-3400 1500);
PAINT AQUA (-3400 1500);
FORCEPROP 1 LAST TOLERANCE 10%
J 2
(-2975 1400);
DISPLAY 0.617021 (-2975 1400);
PAINT SKYBLUE (-2975 1400);
FORCEPROP 1 LAST PACK_TYPE 0402
J 1
(-2875 1400);
DISPLAY 0.617021 (-2875 1400);
PAINT SKYBLUE (-2875 1400);
FORCEPROP 1 LAST MATERIAL X7R
J 0
(-3175 1400);
DISPLAY 0.617021 (-3175 1400);
PAINT SKYBLUE (-3175 1400);
FORCEPROP 1 LAST VOLTAGE 16V
J 0
(-3300 1400);
DISPLAY 0.617021 (-3300 1400);
PAINT SKYBLUE (-3300 1400);
FORCEPROP 1 LASTPIN (-3300 1425) $PN 2
J 0
(-3315 1440);
DISPLAY 0.617021 (-3315 1440);
PAINT ORANGE (-3315 1440);
FORCEPROP 1 LASTPIN (-3500 1425) $PN 1
J 0
(-3510 1440);
DISPLAY 0.617021 (-3510 1440);
PAINT ORANGE (-3510 1440);
FORCEPROP 1 LAST VALUE 0.22UF
J 2
(-3475 1375);
DISPLAY 0.617021 (-3475 1375);
PAINT SKYBLUE (-3475 1375);
FORCEPROP 0 LAST ROOM IO_SLOT
J 0
(-3400 1625);
DISPLAY 1.021277 (-3400 1625);
PAINT ORANGE (-3400 1625);
DISPLAY INVISIBLE (-3400 1625);
FORCEPROP 2 LAST SEC 1
J 0
(-3400 1675);
DISPLAY 0.680851 (-3400 1675);
PAINT MONO (-3400 1675);
DISPLAY INVISIBLE (-3400 1675);
FORCEPROP 2 LAST SEC_TYPE 0402
J 0
(-3400 1675);
DISPLAY 1.021277 (-3400 1675);
PAINT ORANGE (-3400 1675);
DISPLAY INVISIBLE (-3400 1675);
FORCEPROP 0 LAST BOM_COST IO_SLOT
J 0
(-3400 1575);
DISPLAY 1.021277 (-3400 1575);
PAINT ORANGE (-3400 1575);
DISPLAY INVISIBLE (-3400 1575);
FORCEPROP 2 LAST CDS_LOCATION C9N17
J 1
(-3400 1500);
DISPLAY 0.617021 (-3400 1500);
PAINT AQUA (-3400 1500);
DISPLAY INVISIBLE (-3400 1500);
FORCEPROP 2 LAST CDS_LIB mstr_discrete
J 0
(-3400 1425);
PAINT ORANGE (-3400 1425);
DISPLAY INVISIBLE (-3400 1425);
FORCEPROP 0 LAST CDS_SEC 1
J 0
(-3175 1550);
PAINT MONO (-3175 1550);
DISPLAY INVISIBLE (-3175 1550);
FORCEPROP 1 LAST PATH I38
J 0
(-3400 1625);
DISPLAY 0.978723 (-3400 1625);
PAINT WHITE (-3400 1625);
DISPLAY INVISIBLE (-3400 1625);
FORCEADD CAP..2
(-2925 1475);
FORCEPROP 1 LAST LOCATION C9N18
J 1
(-2925 1525);
DISPLAY 0.617021 (-2925 1525);
PAINT AQUA (-2925 1525);
FORCEPROP 1 LAST VALUE 0.22UF
J 2
(-2975 1450);
DISPLAY 0.617021 (-2975 1450);
PAINT SKYBLUE (-2975 1450);
FORCEPROP 1 LASTPIN (-2825 1475) $PN 2
J 0
(-2840 1490);
DISPLAY 0.617021 (-2840 1490);
PAINT ORANGE (-2840 1490);
FORCEPROP 1 LAST PART_NUMBER A36096-155
J 1
(-2625 1500);
DISPLAY 0.617021 (-2625 1500);
PAINT BLUE (-2625 1500);
FORCEPROP 1 LAST MATERIAL X7R
J 0
(-2700 1450);
DISPLAY 0.617021 (-2700 1450);
PAINT SKYBLUE (-2700 1450);
FORCEPROP 1 LAST VOLTAGE 16V
J 0
(-2825 1450);
DISPLAY 0.617021 (-2825 1450);
PAINT SKYBLUE (-2825 1450);
FORCEPROP 1 LAST PACK_TYPE 0402
J 1
(-2400 1450);
DISPLAY 0.617021 (-2400 1450);
PAINT SKYBLUE (-2400 1450);
FORCEPROP 1 LAST TOLERANCE 10%
J 2
(-2500 1450);
DISPLAY 0.617021 (-2500 1450);
PAINT SKYBLUE (-2500 1450);
FORCEPROP 1 LASTPIN (-3025 1475) $PN 1
J 0
(-3035 1490);
DISPLAY 0.617021 (-3035 1490);
PAINT ORANGE (-3035 1490);
FORCEPROP 0 LAST ROOM IO_SLOT
J 0
(-2925 1675);
DISPLAY 1.021277 (-2925 1675);
PAINT ORANGE (-2925 1675);
DISPLAY INVISIBLE (-2925 1675);
FORCEPROP 2 LAST CDS_LOCATION C9N18
J 1
(-2925 1550);
DISPLAY 0.617021 (-2925 1550);
PAINT AQUA (-2925 1550);
DISPLAY INVISIBLE (-2925 1550);
FORCEPROP 2 LAST SEC 1
J 0
(-2925 1725);
DISPLAY 0.680851 (-2925 1725);
PAINT MONO (-2925 1725);
DISPLAY INVISIBLE (-2925 1725);
FORCEPROP 0 LAST BOM_COST IO_SLOT
J 0
(-2925 1625);
DISPLAY 1.021277 (-2925 1625);
PAINT ORANGE (-2925 1625);
DISPLAY INVISIBLE (-2925 1625);
FORCEPROP 2 LAST SEC_TYPE 0402
J 0
(-2925 1725);
DISPLAY 1.021277 (-2925 1725);
PAINT ORANGE (-2925 1725);
DISPLAY INVISIBLE (-2925 1725);
FORCEPROP 2 LAST CDS_LIB mstr_discrete
J 0
(-2925 1475);
PAINT ORANGE (-2925 1475);
DISPLAY INVISIBLE (-2925 1475);
FORCEPROP 0 LAST CDS_SEC 1
J 0
(-2925 1575);
PAINT MONO (-2925 1575);
DISPLAY INVISIBLE (-2925 1575);
FORCEPROP 1 LAST PATH I39
J 0
(-2925 1675);
DISPLAY 0.978723 (-2925 1675);
PAINT WHITE (-2925 1675);
DISPLAY INVISIBLE (-2925 1675);
FORCEADD OFFPAGE..6
(-7875 225);
FORCEPROP 2 LAST $XR3 182 
J 0
(-8155 189);
DISPLAY 0.638298 (-8155 189);
PAINT MONO (-8155 189);
FORCEPROP 2 LAST $XR2 160 
J 0
(-8395 225);
DISPLAY 0.638298 (-8395 225);
PAINT MONO (-8395 225);
FORCEPROP 2 LAST $XR1 156 
J 0
(-8275 225);
DISPLAY 0.638298 (-8275 225);
PAINT MONO (-8275 225);
FORCEPROP 2 LAST $XR0 138 
J 0
(-8155 225);
DISPLAY 0.638298 (-8155 225);
PAINT MONO (-8155 225);
FORCEPROP 1 LAST OFFPAGE TRUE
J 0
(-7550 100);
DISPLAY 0.872340 (-7550 100);
PAINT GREEN (-7550 100);
DISPLAY INVISIBLE (-7550 100);
FORCEPROP 1 LAST COMMENT_BODY TRUE
J 0
(-7775 150);
DISPLAY 0.872340 (-7775 150);
PAINT GREEN (-7775 150);
DISPLAY INVISIBLE (-7775 150);
FORCEPROP 2 LAST CDS_LIB mstr_standard
J 0
(-7875 225);
PAINT ORANGE (-7875 225);
DISPLAY INVISIBLE (-7875 225);
FORCEPROP 2 LAST PATH I4
J 0
(-8150 275);
DISPLAY 1.021277 (-8150 275);
PAINT ORANGE (-8150 275);
DISPLAY INVISIBLE (-8150 275);
FORCEADD CAP..2
(-2925 1175);
FORCEPROP 1 LAST LOCATION C9N1
J 1
(-2900 1225);
DISPLAY 0.617021 (-2900 1225);
PAINT AQUA (-2900 1225);
FORCEPROP 1 LAST VALUE 0.22UF
J 2
(-2975 1150);
DISPLAY 0.617021 (-2975 1150);
PAINT SKYBLUE (-2975 1150);
FORCEPROP 1 LAST PACK_TYPE 0402
J 1
(-2400 1150);
DISPLAY 0.617021 (-2400 1150);
PAINT SKYBLUE (-2400 1150);
FORCEPROP 1 LAST PART_NUMBER A36096-155
J 1
(-2625 1200);
DISPLAY 0.617021 (-2625 1200);
PAINT BLUE (-2625 1200);
FORCEPROP 1 LAST TOLERANCE 10%
J 2
(-2500 1150);
DISPLAY 0.617021 (-2500 1150);
PAINT SKYBLUE (-2500 1150);
FORCEPROP 1 LAST MATERIAL X7R
J 0
(-2700 1150);
DISPLAY 0.617021 (-2700 1150);
PAINT SKYBLUE (-2700 1150);
FORCEPROP 1 LAST VOLTAGE 16V
J 0
(-2825 1150);
DISPLAY 0.617021 (-2825 1150);
PAINT SKYBLUE (-2825 1150);
FORCEPROP 1 LASTPIN (-2825 1175) $PN 2
J 0
(-2840 1190);
DISPLAY 0.617021 (-2840 1190);
PAINT ORANGE (-2840 1190);
FORCEPROP 1 LASTPIN (-3025 1175) $PN 1
J 0
(-3035 1190);
DISPLAY 0.617021 (-3035 1190);
PAINT ORANGE (-3035 1190);
FORCEPROP 2 LAST SEC_TYPE 0402
J 0
(-2925 1425);
DISPLAY 1.021277 (-2925 1425);
PAINT ORANGE (-2925 1425);
DISPLAY INVISIBLE (-2925 1425);
FORCEPROP 2 LAST SEC 1
J 0
(-2925 1425);
DISPLAY 0.680851 (-2925 1425);
PAINT MONO (-2925 1425);
DISPLAY INVISIBLE (-2925 1425);
FORCEPROP 0 LAST ROOM IO_SLOT
J 0
(-2925 1375);
DISPLAY 1.021277 (-2925 1375);
PAINT ORANGE (-2925 1375);
DISPLAY INVISIBLE (-2925 1375);
FORCEPROP 0 LAST BOM_COST IO_SLOT
J 0
(-2925 1325);
DISPLAY 1.021277 (-2925 1325);
PAINT ORANGE (-2925 1325);
DISPLAY INVISIBLE (-2925 1325);
FORCEPROP 2 LAST CDS_LIB mstr_discrete
J 0
(-2925 1175);
PAINT ORANGE (-2925 1175);
DISPLAY INVISIBLE (-2925 1175);
FORCEPROP 2 LAST CDS_LOCATION C9N1
J 1
(-2900 1225);
DISPLAY 0.617021 (-2900 1225);
PAINT AQUA (-2900 1225);
DISPLAY INVISIBLE (-2900 1225);
FORCEPROP 0 LAST CDS_SEC 1
J 0
(-2900 1275);
PAINT MONO (-2900 1275);
DISPLAY INVISIBLE (-2900 1275);
FORCEPROP 1 LAST PATH I40
J 0
(-2925 1375);
DISPLAY 0.978723 (-2925 1375);
PAINT WHITE (-2925 1375);
DISPLAY INVISIBLE (-2925 1375);
FORCEADD CAP..2
(-2925 1325);
FORCEPROP 1 LAST VALUE 0.22UF
J 2
(-2975 1300);
DISPLAY 0.617021 (-2975 1300);
PAINT SKYBLUE (-2975 1300);
FORCEPROP 1 LAST MATERIAL X7R
J 0
(-2700 1300);
DISPLAY 0.617021 (-2700 1300);
PAINT SKYBLUE (-2700 1300);
FORCEPROP 1 LAST PACK_TYPE 0402
J 1
(-2400 1300);
DISPLAY 0.617021 (-2400 1300);
PAINT SKYBLUE (-2400 1300);
FORCEPROP 1 LAST LOCATION C9N15
J 1
(-2925 1375);
DISPLAY 0.617021 (-2925 1375);
PAINT AQUA (-2925 1375);
FORCEPROP 1 LASTPIN (-2825 1325) $PN 2
J 0
(-2840 1340);
DISPLAY 0.617021 (-2840 1340);
PAINT ORANGE (-2840 1340);
FORCEPROP 1 LAST PART_NUMBER A36096-155
J 1
(-2625 1350);
DISPLAY 0.617021 (-2625 1350);
PAINT BLUE (-2625 1350);
FORCEPROP 1 LAST TOLERANCE 10%
J 2
(-2500 1300);
DISPLAY 0.617021 (-2500 1300);
PAINT SKYBLUE (-2500 1300);
FORCEPROP 1 LAST VOLTAGE 16V
J 0
(-2825 1300);
DISPLAY 0.617021 (-2825 1300);
PAINT SKYBLUE (-2825 1300);
FORCEPROP 1 LASTPIN (-3025 1325) $PN 1
J 0
(-3035 1340);
DISPLAY 0.617021 (-3035 1340);
PAINT ORANGE (-3035 1340);
FORCEPROP 2 LAST SEC_TYPE 0402
J 0
(-2925 1575);
DISPLAY 1.021277 (-2925 1575);
PAINT ORANGE (-2925 1575);
DISPLAY INVISIBLE (-2925 1575);
FORCEPROP 2 LAST SEC 1
J 0
(-2925 1575);
DISPLAY 0.680851 (-2925 1575);
PAINT MONO (-2925 1575);
DISPLAY INVISIBLE (-2925 1575);
FORCEPROP 0 LAST ROOM IO_SLOT
J 0
(-2925 1525);
DISPLAY 1.021277 (-2925 1525);
PAINT ORANGE (-2925 1525);
DISPLAY INVISIBLE (-2925 1525);
FORCEPROP 0 LAST BOM_COST IO_SLOT
J 0
(-2925 1475);
DISPLAY 1.021277 (-2925 1475);
PAINT ORANGE (-2925 1475);
DISPLAY INVISIBLE (-2925 1475);
FORCEPROP 2 LAST CDS_LOCATION C9N15
J 1
(-2925 1375);
DISPLAY 0.617021 (-2925 1375);
PAINT AQUA (-2925 1375);
DISPLAY INVISIBLE (-2925 1375);
FORCEPROP 2 LAST CDS_LIB mstr_discrete
J 0
(-2925 1325);
PAINT ORANGE (-2925 1325);
DISPLAY INVISIBLE (-2925 1325);
FORCEPROP 0 LAST CDS_SEC 1
J 0
(-2925 1425);
PAINT MONO (-2925 1425);
DISPLAY INVISIBLE (-2925 1425);
FORCEPROP 1 LAST PATH I41
J 0
(-2925 1525);
DISPLAY 0.978723 (-2925 1525);
PAINT WHITE (-2925 1525);
DISPLAY INVISIBLE (-2925 1525);
FORCEADD CAP..2
(-3400 1725);
FORCEPROP 1 LAST PACK_TYPE 0402
J 1
(-2875 1700);
DISPLAY 0.617021 (-2875 1700);
PAINT SKYBLUE (-2875 1700);
FORCEPROP 1 LAST PART_NUMBER A36096-155
J 1
(-3100 1750);
DISPLAY 0.617021 (-3100 1750);
PAINT BLUE (-3100 1750);
FORCEPROP 1 LAST MATERIAL X7R
J 0
(-3175 1700);
DISPLAY 0.617021 (-3175 1700);
PAINT SKYBLUE (-3175 1700);
FORCEPROP 1 LAST LOCATION C9N6
J 1
(-3400 1650);
DISPLAY 0.617021 (-3400 1650);
PAINT AQUA (-3400 1650);
FORCEPROP 1 LAST TOLERANCE 10%
J 2
(-2975 1700);
DISPLAY 0.617021 (-2975 1700);
PAINT SKYBLUE (-2975 1700);
FORCEPROP 1 LASTPIN (-3500 1725) $PN 1
J 0
(-3510 1740);
DISPLAY 0.617021 (-3510 1740);
PAINT ORANGE (-3510 1740);
FORCEPROP 1 LAST VALUE 0.22UF
J 2
(-3450 1700);
DISPLAY 0.617021 (-3450 1700);
PAINT SKYBLUE (-3450 1700);
FORCEPROP 1 LAST VOLTAGE 16V
J 0
(-3300 1700);
DISPLAY 0.617021 (-3300 1700);
PAINT SKYBLUE (-3300 1700);
FORCEPROP 1 LASTPIN (-3300 1725) $PN 2
J 0
(-3315 1740);
DISPLAY 0.617021 (-3315 1740);
PAINT ORANGE (-3315 1740);
FORCEPROP 2 LAST SEC 1
J 0
(-3400 1975);
DISPLAY 0.680851 (-3400 1975);
PAINT MONO (-3400 1975);
DISPLAY INVISIBLE (-3400 1975);
FORCEPROP 0 LAST ROOM IO_SLOT
J 0
(-3400 1925);
DISPLAY 1.021277 (-3400 1925);
PAINT ORANGE (-3400 1925);
DISPLAY INVISIBLE (-3400 1925);
FORCEPROP 2 LAST SEC_TYPE 0402
J 0
(-3400 1975);
DISPLAY 1.021277 (-3400 1975);
PAINT ORANGE (-3400 1975);
DISPLAY INVISIBLE (-3400 1975);
FORCEPROP 0 LAST BOM_COST IO_SLOT
J 0
(-3400 1875);
DISPLAY 1.021277 (-3400 1875);
PAINT ORANGE (-3400 1875);
DISPLAY INVISIBLE (-3400 1875);
FORCEPROP 2 LAST CDS_LOCATION C9N6
J 1
(-3400 1825);
DISPLAY 0.617021 (-3400 1825);
PAINT AQUA (-3400 1825);
DISPLAY INVISIBLE (-3400 1825);
FORCEPROP 2 LAST CDS_LIB mstr_discrete
J 0
(-3400 1725);
PAINT ORANGE (-3400 1725);
DISPLAY INVISIBLE (-3400 1725);
FORCEPROP 0 LAST CDS_SEC 1
J 0
(-3100 1800);
PAINT MONO (-3100 1800);
DISPLAY INVISIBLE (-3100 1800);
FORCEPROP 1 LAST PATH I42
J 0
(-3400 1925);
DISPLAY 0.978723 (-3400 1925);
PAINT WHITE (-3400 1925);
DISPLAY INVISIBLE (-3400 1925);
FORCEADD CAP..2
(-3400 1825);
FORCEPROP 1 LAST LOCATION C9N14
J 1
(-3400 1900);
DISPLAY 0.617021 (-3400 1900);
PAINT AQUA (-3400 1900);
FORCEPROP 1 LAST PACK_TYPE 0402
J 1
(-2875 1800);
DISPLAY 0.617021 (-2875 1800);
PAINT SKYBLUE (-2875 1800);
FORCEPROP 1 LAST VOLTAGE 16V
J 0
(-3300 1800);
DISPLAY 0.617021 (-3300 1800);
PAINT SKYBLUE (-3300 1800);
FORCEPROP 1 LAST PART_NUMBER A36096-155
J 1
(-3150 1875);
DISPLAY 0.617021 (-3150 1875);
PAINT BLUE (-3150 1875);
FORCEPROP 1 LAST TOLERANCE 10%
J 2
(-2975 1800);
DISPLAY 0.617021 (-2975 1800);
PAINT SKYBLUE (-2975 1800);
FORCEPROP 1 LAST MATERIAL X7R
J 0
(-3175 1800);
DISPLAY 0.617021 (-3175 1800);
PAINT SKYBLUE (-3175 1800);
FORCEPROP 1 LASTPIN (-3300 1825) $PN 2
J 0
(-3315 1840);
DISPLAY 0.617021 (-3315 1840);
PAINT ORANGE (-3315 1840);
FORCEPROP 1 LASTPIN (-3500 1825) $PN 1
J 0
(-3510 1840);
DISPLAY 0.617021 (-3510 1840);
PAINT ORANGE (-3510 1840);
FORCEPROP 1 LAST VALUE 0.22UF
J 2
(-3475 1775);
DISPLAY 0.617021 (-3475 1775);
PAINT SKYBLUE (-3475 1775);
FORCEPROP 2 LAST SEC 1
J 0
(-3400 2075);
DISPLAY 0.680851 (-3400 2075);
PAINT MONO (-3400 2075);
DISPLAY INVISIBLE (-3400 2075);
FORCEPROP 2 LAST SEC_TYPE 0402
J 0
(-3400 2075);
DISPLAY 1.021277 (-3400 2075);
PAINT ORANGE (-3400 2075);
DISPLAY INVISIBLE (-3400 2075);
FORCEPROP 0 LAST ROOM IO_SLOT
J 0
(-3400 2025);
DISPLAY 1.021277 (-3400 2025);
PAINT ORANGE (-3400 2025);
DISPLAY INVISIBLE (-3400 2025);
FORCEPROP 0 LAST BOM_COST IO_SLOT
J 0
(-3400 1975);
DISPLAY 1.021277 (-3400 1975);
PAINT ORANGE (-3400 1975);
DISPLAY INVISIBLE (-3400 1975);
FORCEPROP 2 LAST CDS_LOCATION C9N14
J 1
(-3400 1900);
DISPLAY 0.617021 (-3400 1900);
PAINT AQUA (-3400 1900);
DISPLAY INVISIBLE (-3400 1900);
FORCEPROP 2 LAST CDS_LIB mstr_discrete
J 0
(-3400 1825);
PAINT ORANGE (-3400 1825);
DISPLAY INVISIBLE (-3400 1825);
FORCEPROP 0 LAST CDS_SEC 1
J 0
(-3400 1950);
PAINT MONO (-3400 1950);
DISPLAY INVISIBLE (-3400 1950);
FORCEPROP 1 LAST PATH I43
J 0
(-3400 2025);
DISPLAY 0.978723 (-3400 2025);
PAINT WHITE (-3400 2025);
DISPLAY INVISIBLE (-3400 2025);
FORCEADD CAP..2
(-3400 1975);
FORCEPROP 1 LAST PACK_TYPE 0402
J 1
(-2875 1950);
DISPLAY 0.617021 (-2875 1950);
PAINT SKYBLUE (-2875 1950);
FORCEPROP 1 LAST TOLERANCE 10%
J 2
(-2975 1950);
DISPLAY 0.617021 (-2975 1950);
PAINT SKYBLUE (-2975 1950);
FORCEPROP 1 LAST PART_NUMBER A36096-155
J 1
(-3200 2050);
DISPLAY 0.617021 (-3200 2050);
PAINT BLUE (-3200 2050);
FORCEPROP 1 LAST MATERIAL X7R
J 0
(-3175 1950);
DISPLAY 0.617021 (-3175 1950);
PAINT SKYBLUE (-3175 1950);
FORCEPROP 1 LAST VOLTAGE 16V
J 0
(-3300 1950);
DISPLAY 0.617021 (-3300 1950);
PAINT SKYBLUE (-3300 1950);
FORCEPROP 1 LAST VALUE 0.22UF
J 2
(-3475 1925);
DISPLAY 0.617021 (-3475 1925);
PAINT SKYBLUE (-3475 1925);
FORCEPROP 1 LAST LOCATION C9N4
J 1
(-3400 2050);
DISPLAY 0.617021 (-3400 2050);
PAINT AQUA (-3400 2050);
FORCEPROP 1 LASTPIN (-3300 1975) $PN 2
J 0
(-3315 1990);
DISPLAY 0.617021 (-3315 1990);
PAINT ORANGE (-3315 1990);
FORCEPROP 1 LASTPIN (-3500 1975) $PN 1
J 0
(-3510 1990);
DISPLAY 0.617021 (-3510 1990);
PAINT ORANGE (-3510 1990);
FORCEPROP 0 LAST ROOM IO_SLOT
J 0
(-3400 2175);
DISPLAY 1.021277 (-3400 2175);
PAINT ORANGE (-3400 2175);
DISPLAY INVISIBLE (-3400 2175);
FORCEPROP 2 LAST CDS_LOCATION C9N4
J 1
(-3400 2050);
DISPLAY 0.617021 (-3400 2050);
PAINT AQUA (-3400 2050);
DISPLAY INVISIBLE (-3400 2050);
FORCEPROP 2 LAST SEC 1
J 0
(-3400 2225);
DISPLAY 0.680851 (-3400 2225);
PAINT MONO (-3400 2225);
DISPLAY INVISIBLE (-3400 2225);
FORCEPROP 2 LAST SEC_TYPE 0402
J 0
(-3400 2225);
DISPLAY 1.021277 (-3400 2225);
PAINT ORANGE (-3400 2225);
DISPLAY INVISIBLE (-3400 2225);
FORCEPROP 0 LAST BOM_COST IO_SLOT
J 0
(-3400 2125);
DISPLAY 1.021277 (-3400 2125);
PAINT ORANGE (-3400 2125);
DISPLAY INVISIBLE (-3400 2125);
FORCEPROP 2 LAST CDS_LIB mstr_discrete
J 0
(-3400 1975);
PAINT ORANGE (-3400 1975);
DISPLAY INVISIBLE (-3400 1975);
FORCEPROP 0 LAST CDS_SEC 1
J 0
(-3200 2100);
PAINT MONO (-3200 2100);
DISPLAY INVISIBLE (-3200 2100);
FORCEPROP 1 LAST PATH I44
J 0
(-3400 2175);
DISPLAY 0.978723 (-3400 2175);
PAINT WHITE (-3400 2175);
DISPLAY INVISIBLE (-3400 2175);
FORCEADD CAP..2
(-2925 1675);
FORCEPROP 1 LAST PACK_TYPE 0402
J 1
(-2400 1650);
DISPLAY 0.617021 (-2400 1650);
PAINT SKYBLUE (-2400 1650);
FORCEPROP 1 LAST PART_NUMBER A36096-155
J 1
(-2725 1725);
DISPLAY 0.617021 (-2725 1725);
PAINT BLUE (-2725 1725);
FORCEPROP 1 LAST VALUE 0.22UF
J 2
(-3000 1625);
DISPLAY 0.617021 (-3000 1625);
PAINT SKYBLUE (-3000 1625);
FORCEPROP 1 LAST LOCATION C9N5
J 1
(-2900 1600);
DISPLAY 0.617021 (-2900 1600);
PAINT AQUA (-2900 1600);
FORCEPROP 1 LAST VOLTAGE 16V
J 0
(-2825 1650);
DISPLAY 0.617021 (-2825 1650);
PAINT SKYBLUE (-2825 1650);
FORCEPROP 1 LAST MATERIAL X7R
J 0
(-2700 1650);
DISPLAY 0.617021 (-2700 1650);
PAINT SKYBLUE (-2700 1650);
FORCEPROP 1 LAST TOLERANCE 10%
J 2
(-2500 1650);
DISPLAY 0.617021 (-2500 1650);
PAINT SKYBLUE (-2500 1650);
FORCEPROP 1 LASTPIN (-2825 1675) $PN 2
J 0
(-2840 1690);
DISPLAY 0.617021 (-2840 1690);
PAINT ORANGE (-2840 1690);
FORCEPROP 1 LASTPIN (-3025 1675) $PN 1
J 0
(-3035 1690);
DISPLAY 0.617021 (-3035 1690);
PAINT ORANGE (-3035 1690);
FORCEPROP 0 LAST ROOM IO_SLOT
J 0
(-2925 1875);
DISPLAY 1.021277 (-2925 1875);
PAINT ORANGE (-2925 1875);
DISPLAY INVISIBLE (-2925 1875);
FORCEPROP 2 LAST SEC 1
J 0
(-2925 1925);
DISPLAY 0.680851 (-2925 1925);
PAINT MONO (-2925 1925);
DISPLAY INVISIBLE (-2925 1925);
FORCEPROP 0 LAST BOM_COST IO_SLOT
J 0
(-2925 1825);
DISPLAY 1.021277 (-2925 1825);
PAINT ORANGE (-2925 1825);
DISPLAY INVISIBLE (-2925 1825);
FORCEPROP 2 LAST SEC_TYPE 0402
J 0
(-2925 1925);
DISPLAY 1.021277 (-2925 1925);
PAINT ORANGE (-2925 1925);
DISPLAY INVISIBLE (-2925 1925);
FORCEPROP 2 LAST CDS_LOCATION C9N5
J 1
(-2925 1750);
DISPLAY 0.617021 (-2925 1750);
PAINT AQUA (-2925 1750);
DISPLAY INVISIBLE (-2925 1750);
FORCEPROP 2 LAST CDS_LIB mstr_discrete
J 0
(-2925 1675);
PAINT ORANGE (-2925 1675);
DISPLAY INVISIBLE (-2925 1675);
FORCEPROP 0 LAST CDS_SEC 1
J 0
(-2925 1800);
PAINT MONO (-2925 1800);
DISPLAY INVISIBLE (-2925 1800);
FORCEPROP 1 LAST PATH I45
J 0
(-2925 1875);
DISPLAY 0.978723 (-2925 1875);
PAINT WHITE (-2925 1875);
DISPLAY INVISIBLE (-2925 1875);
FORCEADD CAP..2
(-2925 1875);
FORCEPROP 1 LASTPIN (-2825 1875) $PN 2
J 0
(-2840 1890);
DISPLAY 0.617021 (-2840 1890);
PAINT ORANGE (-2840 1890);
FORCEPROP 1 LAST LOCATION C9N16
J 1
(-2925 1900);
DISPLAY 0.617021 (-2925 1900);
PAINT AQUA (-2925 1900);
FORCEPROP 1 LAST PART_NUMBER A36096-155
J 1
(-2650 1900);
DISPLAY 0.617021 (-2650 1900);
PAINT BLUE (-2650 1900);
FORCEPROP 1 LAST PACK_TYPE 0402
J 1
(-2400 1850);
DISPLAY 0.617021 (-2400 1850);
PAINT SKYBLUE (-2400 1850);
FORCEPROP 1 LAST TOLERANCE 10%
J 2
(-2500 1850);
DISPLAY 0.617021 (-2500 1850);
PAINT SKYBLUE (-2500 1850);
FORCEPROP 1 LAST MATERIAL X7R
J 0
(-2700 1850);
DISPLAY 0.617021 (-2700 1850);
PAINT SKYBLUE (-2700 1850);
FORCEPROP 1 LAST VOLTAGE 16V
J 0
(-2825 1850);
DISPLAY 0.617021 (-2825 1850);
PAINT SKYBLUE (-2825 1850);
FORCEPROP 1 LAST VALUE 0.22UF
J 2
(-2975 1850);
DISPLAY 0.617021 (-2975 1850);
PAINT SKYBLUE (-2975 1850);
FORCEPROP 1 LASTPIN (-3025 1875) $PN 1
J 0
(-3035 1890);
DISPLAY 0.617021 (-3035 1890);
PAINT ORANGE (-3035 1890);
FORCEPROP 0 LAST ROOM IO_SLOT
J 0
(-2925 2075);
DISPLAY 1.021277 (-2925 2075);
PAINT ORANGE (-2925 2075);
DISPLAY INVISIBLE (-2925 2075);
FORCEPROP 2 LAST SEC 1
J 0
(-2925 2125);
DISPLAY 0.680851 (-2925 2125);
PAINT MONO (-2925 2125);
DISPLAY INVISIBLE (-2925 2125);
FORCEPROP 2 LAST SEC_TYPE 0402
J 0
(-2925 2125);
DISPLAY 1.021277 (-2925 2125);
PAINT ORANGE (-2925 2125);
DISPLAY INVISIBLE (-2925 2125);
FORCEPROP 0 LAST BOM_COST IO_SLOT
J 0
(-2925 2025);
DISPLAY 1.021277 (-2925 2025);
PAINT ORANGE (-2925 2025);
DISPLAY INVISIBLE (-2925 2025);
FORCEPROP 2 LAST CDS_LOCATION C9N16
J 1
(-2925 1975);
DISPLAY 0.617021 (-2925 1975);
PAINT AQUA (-2925 1975);
DISPLAY INVISIBLE (-2925 1975);
FORCEPROP 2 LAST CDS_LIB mstr_discrete
J 0
(-2925 1875);
PAINT ORANGE (-2925 1875);
DISPLAY INVISIBLE (-2925 1875);
FORCEPROP 0 LAST CDS_SEC 1
J 0
(-2650 1950);
PAINT MONO (-2650 1950);
DISPLAY INVISIBLE (-2650 1950);
FORCEPROP 1 LAST PATH I46
J 0
(-2925 2075);
DISPLAY 0.978723 (-2925 2075);
PAINT WHITE (-2925 2075);
DISPLAY INVISIBLE (-2925 2075);
FORCEADD CAP..2
(-2925 2025);
FORCEPROP 1 LAST LOCATION C9N3
J 1
(-2925 2075);
DISPLAY 0.617021 (-2925 2075);
PAINT AQUA (-2925 2075);
FORCEPROP 1 LAST TOLERANCE 10%
J 2
(-2500 2000);
DISPLAY 0.617021 (-2500 2000);
PAINT SKYBLUE (-2500 2000);
FORCEPROP 1 LAST PART_NUMBER A36096-155
J 1
(-2650 2050);
DISPLAY 0.617021 (-2650 2050);
PAINT BLUE (-2650 2050);
FORCEPROP 1 LAST PACK_TYPE 0402
J 1
(-2400 2000);
DISPLAY 0.617021 (-2400 2000);
PAINT SKYBLUE (-2400 2000);
FORCEPROP 1 LAST MATERIAL X7R
J 0
(-2700 2000);
DISPLAY 0.617021 (-2700 2000);
PAINT SKYBLUE (-2700 2000);
FORCEPROP 1 LAST VALUE 0.22UF
J 2
(-2975 2000);
DISPLAY 0.617021 (-2975 2000);
PAINT SKYBLUE (-2975 2000);
FORCEPROP 1 LASTPIN (-3025 2025) $PN 1
J 0
(-3035 2040);
DISPLAY 0.617021 (-3035 2040);
PAINT ORANGE (-3035 2040);
FORCEPROP 1 LASTPIN (-2825 2025) $PN 2
J 0
(-2840 2040);
DISPLAY 0.617021 (-2840 2040);
PAINT ORANGE (-2840 2040);
FORCEPROP 1 LAST VOLTAGE 16V
J 0
(-2825 2000);
DISPLAY 0.617021 (-2825 2000);
PAINT SKYBLUE (-2825 2000);
FORCEPROP 2 LAST SEC_TYPE 0402
J 0
(-2925 2275);
DISPLAY 1.021277 (-2925 2275);
PAINT ORANGE (-2925 2275);
DISPLAY INVISIBLE (-2925 2275);
FORCEPROP 2 LAST SEC 1
J 0
(-2925 2275);
DISPLAY 0.680851 (-2925 2275);
PAINT MONO (-2925 2275);
DISPLAY INVISIBLE (-2925 2275);
FORCEPROP 0 LAST ROOM IO_SLOT
J 0
(-2925 2225);
DISPLAY 1.021277 (-2925 2225);
PAINT ORANGE (-2925 2225);
DISPLAY INVISIBLE (-2925 2225);
FORCEPROP 2 LAST CDS_LOCATION C9N3
J 1
(-2925 2125);
DISPLAY 0.617021 (-2925 2125);
PAINT AQUA (-2925 2125);
DISPLAY INVISIBLE (-2925 2125);
FORCEPROP 0 LAST BOM_COST IO_SLOT
J 0
(-2925 2175);
DISPLAY 1.021277 (-2925 2175);
PAINT ORANGE (-2925 2175);
DISPLAY INVISIBLE (-2925 2175);
FORCEPROP 2 LAST CDS_LIB mstr_discrete
J 0
(-2925 2025);
PAINT ORANGE (-2925 2025);
DISPLAY INVISIBLE (-2925 2025);
FORCEPROP 0 LAST CDS_SEC 1
J 0
(-2925 2125);
PAINT MONO (-2925 2125);
DISPLAY INVISIBLE (-2925 2125);
FORCEPROP 1 LAST PATH I47
J 0
(-2925 2225);
DISPLAY 0.978723 (-2925 2225);
PAINT WHITE (-2925 2225);
DISPLAY INVISIBLE (-2925 2225);
FORCEADD CAP..2
(-3400 2175);
FORCEPROP 1 LAST TOLERANCE 10%
J 2
(-2975 2150);
DISPLAY 0.617021 (-2975 2150);
PAINT SKYBLUE (-2975 2150);
FORCEPROP 1 LAST PACK_TYPE 0402
J 1
(-2875 2150);
DISPLAY 0.617021 (-2875 2150);
PAINT SKYBLUE (-2875 2150);
FORCEPROP 1 LAST MATERIAL X7R
J 0
(-3175 2150);
DISPLAY 0.617021 (-3175 2150);
PAINT SKYBLUE (-3175 2150);
FORCEPROP 1 LAST VOLTAGE 16V
J 0
(-3300 2150);
DISPLAY 0.617021 (-3300 2150);
PAINT SKYBLUE (-3300 2150);
FORCEPROP 1 LASTPIN (-3300 2175) $PN 2
J 0
(-3315 2190);
DISPLAY 0.617021 (-3315 2190);
PAINT ORANGE (-3315 2190);
FORCEPROP 1 LAST VALUE 0.22UF
J 2
(-3475 2125);
DISPLAY 0.617021 (-3475 2125);
PAINT SKYBLUE (-3475 2125);
FORCEPROP 1 LAST PART_NUMBER A36096-155
J 1
(-3250 2225);
DISPLAY 0.617021 (-3250 2225);
PAINT BLUE (-3250 2225);
FORCEPROP 1 LAST LOCATION C9N7
J 1
(-3400 2250);
DISPLAY 0.617021 (-3400 2250);
PAINT AQUA (-3400 2250);
FORCEPROP 1 LASTPIN (-3500 2175) $PN 1
J 0
(-3510 2190);
DISPLAY 0.617021 (-3510 2190);
PAINT ORANGE (-3510 2190);
FORCEPROP 0 LAST ROOM IO_SLOT
J 0
(-3400 2375);
DISPLAY 1.021277 (-3400 2375);
PAINT ORANGE (-3400 2375);
DISPLAY INVISIBLE (-3400 2375);
FORCEPROP 2 LAST SEC 1
J 0
(-3400 2425);
DISPLAY 0.680851 (-3400 2425);
PAINT MONO (-3400 2425);
DISPLAY INVISIBLE (-3400 2425);
FORCEPROP 0 LAST BOM_COST IO_SLOT
J 0
(-3400 2325);
DISPLAY 1.021277 (-3400 2325);
PAINT ORANGE (-3400 2325);
DISPLAY INVISIBLE (-3400 2325);
FORCEPROP 2 LAST SEC_TYPE 0402
J 0
(-3400 2425);
DISPLAY 1.021277 (-3400 2425);
PAINT ORANGE (-3400 2425);
DISPLAY INVISIBLE (-3400 2425);
FORCEPROP 2 LAST CDS_LIB mstr_discrete
J 0
(-3400 2175);
PAINT ORANGE (-3400 2175);
DISPLAY INVISIBLE (-3400 2175);
FORCEPROP 2 LAST CDS_LOCATION C9N7
J 1
(-3400 2250);
DISPLAY 0.617021 (-3400 2250);
PAINT AQUA (-3400 2250);
DISPLAY INVISIBLE (-3400 2250);
FORCEPROP 0 LAST CDS_SEC 1
J 0
(-3400 2300);
PAINT MONO (-3400 2300);
DISPLAY INVISIBLE (-3400 2300);
FORCEPROP 1 LAST PATH I48
J 0
(-3400 2375);
DISPLAY 0.978723 (-3400 2375);
PAINT WHITE (-3400 2375);
DISPLAY INVISIBLE (-3400 2375);
FORCEADD CAP..2
(-3400 2325);
FORCEPROP 1 LAST MATERIAL X7R
J 0
(-3175 2300);
DISPLAY 0.617021 (-3175 2300);
PAINT SKYBLUE (-3175 2300);
FORCEPROP 1 LAST VOLTAGE 16V
J 0
(-3300 2300);
DISPLAY 0.617021 (-3300 2300);
PAINT SKYBLUE (-3300 2300);
FORCEPROP 1 LAST TOLERANCE 10%
J 2
(-2975 2300);
DISPLAY 0.617021 (-2975 2300);
PAINT SKYBLUE (-2975 2300);
FORCEPROP 1 LAST PACK_TYPE 0402
J 1
(-2875 2300);
DISPLAY 0.617021 (-2875 2300);
PAINT SKYBLUE (-2875 2300);
FORCEPROP 1 LAST VALUE 0.22UF
J 2
(-3475 2275);
DISPLAY 0.617021 (-3475 2275);
PAINT SKYBLUE (-3475 2275);
FORCEPROP 1 LASTPIN (-3500 2325) $PN 1
J 0
(-3510 2340);
DISPLAY 0.617021 (-3510 2340);
PAINT ORANGE (-3510 2340);
FORCEPROP 1 LAST LOCATION C9N10
J 1
(-3400 2375);
DISPLAY 0.617021 (-3400 2375);
PAINT AQUA (-3400 2375);
FORCEPROP 1 LASTPIN (-3300 2325) $PN 2
J 0
(-3315 2340);
DISPLAY 0.617021 (-3315 2340);
PAINT ORANGE (-3315 2340);
FORCEPROP 1 LAST PART_NUMBER A36096-155
J 1
(-3775 2275);
DISPLAY 0.617021 (-3775 2275);
PAINT BLUE (-3775 2275);
FORCEPROP 2 LAST SEC_TYPE 0402
J 0
(-3400 2575);
DISPLAY 1.021277 (-3400 2575);
PAINT ORANGE (-3400 2575);
DISPLAY INVISIBLE (-3400 2575);
FORCEPROP 2 LAST SEC 1
J 0
(-3400 2575);
DISPLAY 0.680851 (-3400 2575);
PAINT MONO (-3400 2575);
DISPLAY INVISIBLE (-3400 2575);
FORCEPROP 0 LAST ROOM IO_SLOT
J 0
(-3400 2525);
DISPLAY 1.021277 (-3400 2525);
PAINT ORANGE (-3400 2525);
DISPLAY INVISIBLE (-3400 2525);
FORCEPROP 0 LAST BOM_COST IO_SLOT
J 0
(-3400 2475);
DISPLAY 1.021277 (-3400 2475);
PAINT ORANGE (-3400 2475);
DISPLAY INVISIBLE (-3400 2475);
FORCEPROP 2 LAST CDS_LIB mstr_discrete
J 0
(-3400 2325);
PAINT ORANGE (-3400 2325);
DISPLAY INVISIBLE (-3400 2325);
FORCEPROP 2 LAST CDS_LOCATION C9N10
J 1
(-3400 2425);
DISPLAY 0.617021 (-3400 2425);
PAINT AQUA (-3400 2425);
DISPLAY INVISIBLE (-3400 2425);
FORCEPROP 0 LAST CDS_SEC 1
J 0
(-3400 2425);
PAINT MONO (-3400 2425);
DISPLAY INVISIBLE (-3400 2425);
FORCEPROP 1 LAST PATH I49
J 0
(-3400 2525);
DISPLAY 0.978723 (-3400 2525);
PAINT WHITE (-3400 2525);
DISPLAY INVISIBLE (-3400 2525);
FORCEADD OFFPAGE..1
(-7875 350);
FORCEPROP 2 LAST $XR3 182 
J 0
(-8127 314);
DISPLAY 0.638298 (-8127 314);
PAINT MONO (-8127 314);
FORCEPROP 2 LAST $XR2 156 
J 0
(-8367 350);
DISPLAY 0.638298 (-8367 350);
PAINT MONO (-8367 350);
FORCEPROP 2 LAST $XR1 160 
J 0
(-8247 350);
DISPLAY 0.638298 (-8247 350);
PAINT MONO (-8247 350);
FORCEPROP 2 LAST $XR0 138 
J 0
(-8127 350);
DISPLAY 0.638298 (-8127 350);
PAINT MONO (-8127 350);
FORCEPROP 1 LAST OFFPAGE TRUE
J 0
(-7550 225);
DISPLAY 0.872340 (-7550 225);
PAINT GREEN (-7550 225);
DISPLAY INVISIBLE (-7550 225);
FORCEPROP 1 LAST COMMENT_BODY TRUE
J 0
(-7750 250);
DISPLAY 0.872340 (-7750 250);
PAINT GREEN (-7750 250);
DISPLAY INVISIBLE (-7750 250);
FORCEPROP 2 LAST CDS_LIB mstr_standard
J 0
(-7875 350);
PAINT ORANGE (-7875 350);
DISPLAY INVISIBLE (-7875 350);
FORCEPROP 2 LAST PATH I5
J 0
(-8125 400);
DISPLAY 1.021277 (-8125 400);
PAINT ORANGE (-8125 400);
DISPLAY INVISIBLE (-8125 400);
FORCEADD OFFPAGE..1
R 2
(-3250 2475);
FORCEPROP 2 LAST $XR1 163 
J 0
(-2914 2475);
DISPLAY 0.638298 (-2914 2475);
PAINT MONO (-2914 2475);
FORCEPROP 2 LAST $XR0 145 
J 0
(-3034 2475);
DISPLAY 0.638298 (-3034 2475);
PAINT MONO (-3034 2475);
FORCEPROP 2 LAST CDS_LIB mstr_standard
J 0
(-3250 2475);
PAINT MONO (-3250 2475);
DISPLAY INVISIBLE (-3250 2475);
FORCEPROP 1 LAST COMMENT_BODY TRUE
J 2
(-3375 2375);
DISPLAY 0.872340 (-3375 2375);
PAINT GREEN (-3375 2375);
DISPLAY INVISIBLE (-3375 2375);
FORCEPROP 1 LAST OFFPAGE TRUE
J 2
(-3575 2350);
DISPLAY 0.872340 (-3575 2350);
PAINT GREEN (-3575 2350);
DISPLAY INVISIBLE (-3575 2350);
FORCEPROP 2 LAST PATH I50
J 0
(-2900 2525);
DISPLAY 1.021277 (-2900 2525);
PAINT ORANGE (-2900 2525);
DISPLAY INVISIBLE (-2900 2525);
FORCEADD OFFPAGE..3
(-3250 2525);
FORCEPROP 2 LAST $XR1 163 
J 0
(-2916 2525);
DISPLAY 0.638298 (-2916 2525);
PAINT MONO (-2916 2525);
FORCEPROP 2 LAST $XR0 145 
J 0
(-3036 2525);
DISPLAY 0.638298 (-3036 2525);
PAINT MONO (-3036 2525);
FORCEPROP 2 LAST CDS_LIB mstr_standard
J 0
(-3250 2525);
PAINT MONO (-3250 2525);
DISPLAY INVISIBLE (-3250 2525);
FORCEPROP 1 LAST OFFPAGE TRUE
J 0
(-2925 2400);
DISPLAY 0.872340 (-2925 2400);
PAINT GREEN (-2925 2400);
DISPLAY INVISIBLE (-2925 2400);
FORCEPROP 1 LAST COMMENT_BODY TRUE
J 0
(-3300 2425);
DISPLAY 0.872340 (-3300 2425);
PAINT GREEN (-3300 2425);
DISPLAY INVISIBLE (-3300 2425);
FORCEPROP 2 LAST PATH I51
J 0
(-2900 2575);
DISPLAY 1.021277 (-2900 2575);
PAINT ORANGE (-2900 2575);
DISPLAY INVISIBLE (-2900 2575);
FORCEADD CAP..2
(-2925 2225);
FORCEPROP 1 LAST VALUE 0.22UF
J 2
(-2975 2200);
DISPLAY 0.617021 (-2975 2200);
PAINT SKYBLUE (-2975 2200);
FORCEPROP 1 LASTPIN (-3025 2225) $PN 1
J 0
(-3035 2240);
DISPLAY 0.617021 (-3035 2240);
PAINT ORANGE (-3035 2240);
FORCEPROP 1 LAST LOCATION C9N9
J 1
(-2925 2275);
DISPLAY 0.617021 (-2925 2275);
PAINT AQUA (-2925 2275);
FORCEPROP 1 LASTPIN (-2825 2225) $PN 2
J 0
(-2840 2240);
DISPLAY 0.617021 (-2840 2240);
PAINT ORANGE (-2840 2240);
FORCEPROP 1 LAST PART_NUMBER A36096-155
J 1
(-2650 2250);
DISPLAY 0.617021 (-2650 2250);
PAINT BLUE (-2650 2250);
FORCEPROP 1 LAST TOLERANCE 10%
J 2
(-2500 2200);
DISPLAY 0.617021 (-2500 2200);
PAINT SKYBLUE (-2500 2200);
FORCEPROP 1 LAST MATERIAL X7R
J 0
(-2700 2200);
DISPLAY 0.617021 (-2700 2200);
PAINT SKYBLUE (-2700 2200);
FORCEPROP 1 LAST VOLTAGE 16V
J 0
(-2825 2200);
DISPLAY 0.617021 (-2825 2200);
PAINT SKYBLUE (-2825 2200);
FORCEPROP 1 LAST PACK_TYPE 0402
J 1
(-2400 2200);
DISPLAY 0.617021 (-2400 2200);
PAINT SKYBLUE (-2400 2200);
FORCEPROP 0 LAST ROOM IO_SLOT
J 0
(-2925 2425);
DISPLAY 1.021277 (-2925 2425);
PAINT ORANGE (-2925 2425);
DISPLAY INVISIBLE (-2925 2425);
FORCEPROP 2 LAST CDS_LOCATION C9N9
J 1
(-2925 2325);
DISPLAY 0.617021 (-2925 2325);
PAINT AQUA (-2925 2325);
DISPLAY INVISIBLE (-2925 2325);
FORCEPROP 2 LAST SEC 1
J 0
(-2925 2475);
DISPLAY 0.680851 (-2925 2475);
PAINT MONO (-2925 2475);
DISPLAY INVISIBLE (-2925 2475);
FORCEPROP 2 LAST SEC_TYPE 0402
J 0
(-2925 2475);
DISPLAY 1.021277 (-2925 2475);
PAINT ORANGE (-2925 2475);
DISPLAY INVISIBLE (-2925 2475);
FORCEPROP 0 LAST BOM_COST IO_SLOT
J 0
(-2925 2375);
DISPLAY 1.021277 (-2925 2375);
PAINT ORANGE (-2925 2375);
DISPLAY INVISIBLE (-2925 2375);
FORCEPROP 2 LAST CDS_LIB mstr_discrete
J 0
(-2925 2225);
PAINT ORANGE (-2925 2225);
DISPLAY INVISIBLE (-2925 2225);
FORCEPROP 0 LAST CDS_SEC 1
J 0
(-2925 2325);
PAINT MONO (-2925 2325);
DISPLAY INVISIBLE (-2925 2325);
FORCEPROP 1 LAST PATH I52
J 0
(-2925 2425);
DISPLAY 0.978723 (-2925 2425);
PAINT WHITE (-2925 2425);
DISPLAY INVISIBLE (-2925 2425);
FORCEADD CAP..2
(-2925 2375);
FORCEPROP 1 LAST VOLTAGE 16V
J 0
(-2825 2350);
DISPLAY 0.617021 (-2825 2350);
PAINT SKYBLUE (-2825 2350);
FORCEPROP 1 LAST PART_NUMBER A36096-155
J 1
(-2650 2400);
DISPLAY 0.617021 (-2650 2400);
PAINT BLUE (-2650 2400);
FORCEPROP 1 LASTPIN (-3025 2375) $PN 1
J 0
(-3035 2390);
DISPLAY 0.617021 (-3035 2390);
PAINT ORANGE (-3035 2390);
FORCEPROP 1 LAST LOCATION C9N8
J 1
(-2925 2425);
DISPLAY 0.617021 (-2925 2425);
PAINT AQUA (-2925 2425);
FORCEPROP 1 LASTPIN (-2825 2375) $PN 2
J 0
(-2840 2390);
DISPLAY 0.617021 (-2840 2390);
PAINT ORANGE (-2840 2390);
FORCEPROP 1 LAST MATERIAL X7R
J 0
(-2700 2350);
DISPLAY 0.617021 (-2700 2350);
PAINT SKYBLUE (-2700 2350);
FORCEPROP 1 LAST TOLERANCE 10%
J 2
(-2500 2350);
DISPLAY 0.617021 (-2500 2350);
PAINT SKYBLUE (-2500 2350);
FORCEPROP 1 LAST PACK_TYPE 0402
J 1
(-2400 2350);
DISPLAY 0.617021 (-2400 2350);
PAINT SKYBLUE (-2400 2350);
FORCEPROP 1 LAST VALUE 0.22UF
J 2
(-2975 2350);
DISPLAY 0.617021 (-2975 2350);
PAINT SKYBLUE (-2975 2350);
FORCEPROP 2 LAST SEC_TYPE 0402
J 0
(-2925 2625);
DISPLAY 1.021277 (-2925 2625);
PAINT ORANGE (-2925 2625);
DISPLAY INVISIBLE (-2925 2625);
FORCEPROP 2 LAST SEC 1
J 0
(-2925 2625);
DISPLAY 0.680851 (-2925 2625);
PAINT MONO (-2925 2625);
DISPLAY INVISIBLE (-2925 2625);
FORCEPROP 0 LAST ROOM IO_SLOT
J 0
(-2925 2575);
DISPLAY 1.021277 (-2925 2575);
PAINT ORANGE (-2925 2575);
DISPLAY INVISIBLE (-2925 2575);
FORCEPROP 0 LAST BOM_COST IO_SLOT
J 0
(-2925 2525);
DISPLAY 1.021277 (-2925 2525);
PAINT ORANGE (-2925 2525);
DISPLAY INVISIBLE (-2925 2525);
FORCEPROP 2 LAST CDS_LOCATION C9N8
J 1
(-2925 2425);
DISPLAY 0.617021 (-2925 2425);
PAINT AQUA (-2925 2425);
DISPLAY INVISIBLE (-2925 2425);
FORCEPROP 2 LAST CDS_LIB mstr_discrete
J 0
(-2925 2375);
PAINT ORANGE (-2925 2375);
DISPLAY INVISIBLE (-2925 2375);
FORCEPROP 0 LAST CDS_SEC 1
J 0
(-2925 2475);
PAINT MONO (-2925 2475);
DISPLAY INVISIBLE (-2925 2475);
FORCEPROP 1 LAST PATH I53
J 0
(-2925 2575);
DISPLAY 0.978723 (-2925 2575);
PAINT WHITE (-2925 2575);
DISPLAY INVISIBLE (-2925 2575);
FORCEADD OFFPAGE..2
(-3250 2725);
FORCEPROP 2 LAST $XR3 147 
J 0
(-2701 2725);
DISPLAY 0.638298 (-2701 2725);
PAINT MONO (-2701 2725);
FORCEPROP 2 LAST $XR2 119 
J 0
(-2821 2725);
DISPLAY 0.638298 (-2821 2725);
PAINT MONO (-2821 2725);
FORCEPROP 2 LAST $XR1 182 
J 0
(-2941 2725);
DISPLAY 0.638298 (-2941 2725);
PAINT MONO (-2941 2725);
FORCEPROP 2 LAST $XR0 133 
J 0
(-3061 2725);
DISPLAY 0.638298 (-3061 2725);
PAINT MONO (-3061 2725);
FORCEPROP 1 LAST OFFPAGE TRUE
J 0
(-2925 2600);
DISPLAY 0.872340 (-2925 2600);
PAINT GREEN (-2925 2600);
DISPLAY INVISIBLE (-2925 2600);
FORCEPROP 2 LAST CDS_LIB mstr_standard
J 0
(-3250 2725);
PAINT MONO (-3250 2725);
DISPLAY INVISIBLE (-3250 2725);
FORCEPROP 1 LAST COMMENT_BODY TRUE
J 0
(-3295 2630);
DISPLAY 0.872340 (-3295 2630);
PAINT GREEN (-3295 2630);
DISPLAY INVISIBLE (-3295 2630);
FORCEPROP 2 LAST PATH I54
J 0
(-2700 2775);
DISPLAY 1.021277 (-2700 2775);
PAINT ORANGE (-2700 2775);
DISPLAY INVISIBLE (-2700 2775);
FORCEADD OFFPAGE..2
(-3250 2775);
FORCEPROP 2 LAST $XR2 147 
J 0
(-2821 2775);
DISPLAY 0.638298 (-2821 2775);
PAINT MONO (-2821 2775);
FORCEPROP 2 LAST $XR1 119 
J 0
(-2941 2775);
DISPLAY 0.638298 (-2941 2775);
PAINT MONO (-2941 2775);
FORCEPROP 2 LAST $XR0 133 
J 0
(-3061 2775);
DISPLAY 0.638298 (-3061 2775);
PAINT MONO (-3061 2775);
FORCEPROP 1 LAST OFFPAGE TRUE
J 0
(-2925 2650);
DISPLAY 0.872340 (-2925 2650);
PAINT GREEN (-2925 2650);
DISPLAY INVISIBLE (-2925 2650);
FORCEPROP 2 LAST CDS_LIB mstr_standard
J 0
(-3250 2775);
PAINT MONO (-3250 2775);
DISPLAY INVISIBLE (-3250 2775);
FORCEPROP 1 LAST COMMENT_BODY TRUE
J 0
(-3295 2680);
DISPLAY 0.872340 (-3295 2680);
PAINT GREEN (-3295 2680);
DISPLAY INVISIBLE (-3295 2680);
FORCEPROP 2 LAST PATH I55
J 0
(-2800 2825);
DISPLAY 1.021277 (-2800 2825);
PAINT ORANGE (-2800 2825);
DISPLAY INVISIBLE (-2800 2825);
FORCEADD OFFPAGE..1
R 2
(-3225 3025);
FORCEPROP 2 LAST $XR3 182 
J 0
(-2679 3025);
DISPLAY 0.638298 (-2679 3025);
PAINT MONO (-2679 3025);
FORCEPROP 2 LAST $XR2 145 
J 0
(-2799 3025);
DISPLAY 0.638298 (-2799 3025);
PAINT MONO (-2799 3025);
FORCEPROP 2 LAST $XR1 133 
J 0
(-2919 3025);
DISPLAY 0.638298 (-2919 3025);
PAINT MONO (-2919 3025);
FORCEPROP 2 LAST $XR0 120 
J 0
(-3039 3025);
DISPLAY 0.638298 (-3039 3025);
PAINT MONO (-3039 3025);
FORCEPROP 2 LAST CDS_LIB mstr_standard
J 0
(-3225 3025);
PAINT MONO (-3225 3025);
DISPLAY INVISIBLE (-3225 3025);
FORCEPROP 1 LAST COMMENT_BODY TRUE
J 2
(-3350 2925);
DISPLAY 0.872340 (-3350 2925);
PAINT GREEN (-3350 2925);
DISPLAY INVISIBLE (-3350 2925);
FORCEPROP 1 LAST OFFPAGE TRUE
J 2
(-3550 2900);
DISPLAY 0.872340 (-3550 2900);
PAINT GREEN (-3550 2900);
DISPLAY INVISIBLE (-3550 2900);
FORCEPROP 2 LAST PATH I56
J 0
(-2675 3075);
DISPLAY 1.021277 (-2675 3075);
PAINT ORANGE (-2675 3075);
DISPLAY INVISIBLE (-2675 3075);
FORCEADD OFFPAGE..6
R 2
(-3225 2925);
FORCEPROP 2 LAST $XR3 182 
J 0
(-2651 2925);
DISPLAY 0.638298 (-2651 2925);
PAINT MONO (-2651 2925);
FORCEPROP 2 LAST $XR2 160 
J 0
(-2771 2925);
DISPLAY 0.638298 (-2771 2925);
PAINT MONO (-2771 2925);
FORCEPROP 2 LAST $XR1 156 
J 0
(-2891 2925);
DISPLAY 0.638298 (-2891 2925);
PAINT MONO (-2891 2925);
FORCEPROP 2 LAST $XR0 138 
J 0
(-3011 2925);
DISPLAY 0.638298 (-3011 2925);
PAINT MONO (-3011 2925);
FORCEPROP 2 LAST CDS_LIB mstr_standard
J 0
(-3225 2925);
PAINT MONO (-3225 2925);
DISPLAY INVISIBLE (-3225 2925);
FORCEPROP 1 LAST COMMENT_BODY TRUE
J 2
(-3325 2850);
DISPLAY 0.872340 (-3325 2850);
PAINT GREEN (-3325 2850);
DISPLAY INVISIBLE (-3325 2850);
FORCEPROP 1 LAST OFFPAGE TRUE
J 2
(-3550 2800);
DISPLAY 0.872340 (-3550 2800);
PAINT GREEN (-3550 2800);
DISPLAY INVISIBLE (-3550 2800);
FORCEPROP 2 LAST PATH I57
J 0
(-2650 2975);
DISPLAY 1.021277 (-2650 2975);
PAINT ORANGE (-2650 2975);
DISPLAY INVISIBLE (-2650 2975);
FORCEADD OFFPAGE..4
(-3225 2875);
FORCEPROP 2 LAST $XR3 182 
J 0
(-2679 2875);
DISPLAY 0.638298 (-2679 2875);
PAINT MONO (-2679 2875);
FORCEPROP 2 LAST $XR2 156 
J 0
(-2799 2875);
DISPLAY 0.638298 (-2799 2875);
PAINT MONO (-2799 2875);
FORCEPROP 2 LAST $XR1 160 
J 0
(-2919 2875);
DISPLAY 0.638298 (-2919 2875);
PAINT MONO (-2919 2875);
FORCEPROP 2 LAST $XR0 138 
J 0
(-3039 2875);
DISPLAY 0.638298 (-3039 2875);
PAINT MONO (-3039 2875);
FORCEPROP 1 LAST OFFPAGE TRUE
J 0
(-2900 2750);
DISPLAY 0.872340 (-2900 2750);
PAINT GREEN (-2900 2750);
DISPLAY INVISIBLE (-2900 2750);
FORCEPROP 2 LAST CDS_LIB mstr_standard
J 0
(-3225 2875);
PAINT MONO (-3225 2875);
DISPLAY INVISIBLE (-3225 2875);
FORCEPROP 1 LAST COMMENT_BODY TRUE
J 0
(-3250 2775);
DISPLAY 0.872340 (-3250 2775);
PAINT GREEN (-3250 2775);
DISPLAY INVISIBLE (-3250 2775);
FORCEPROP 2 LAST PATH I58
J 0
(-2675 2925);
DISPLAY 1.021277 (-2675 2925);
PAINT ORANGE (-2675 2925);
DISPLAY INVISIBLE (-2675 2925);
FORCEADD TAP..6
R 2
(-2175 1175);
FORCEPROP 3 LASTPIN (-2225 1175) SIG_NAME P3E_CPU1_PE3_MP_TXP<10>
J 0
(-2215 1185);
DISPLAY 0.659574 (-2215 1185);
PAINT MONO (-2215 1185);
DISPLAY INVISIBLE (-2215 1185);
FORCEPROP 1 LASTPIN (-2225 1175) BN 10
J 2
(-2173 1183);
DISPLAY 0.617021 (-2173 1183);
PAINT GREEN (-2173 1183);
FORCEPROP 2 LAST CDS_LIB mstr_standard
J 0
(-2175 1175);
PAINT ORANGE (-2175 1175);
DISPLAY INVISIBLE (-2175 1175);
FORCEPROP 1 LAST BODY_TYPE PLUMBING
J 2
(-2175 1125);
DISPLAY 1.234043 (-2175 1125);
PAINT GREEN (-2175 1125);
DISPLAY INVISIBLE (-2175 1125);
FORCEPROP 1 LAST HDL_TAP TRUE
J 2
(-2500 1050);
DISPLAY 1.234043 (-2500 1050);
PAINT GREEN (-2500 1050);
DISPLAY INVISIBLE (-2500 1050);
FORCEPROP 1 LAST PATH I59
J 2
(-2173 1175);
DISPLAY 0.872340 (-2173 1175);
PAINT GREEN (-2173 1175);
DISPLAY INVISIBLE (-2173 1175);
FORCEADD RES..1
(-7000 -175);
FORCEPROP 1 LAST PACK_TYPE 0402
J 0
(-6750 -225);
DISPLAY 0.617021 (-6750 -225);
PAINT SKYBLUE (-6750 -225);
FORCEPROP 1 LAST MATERIAL EMPTY
J 0
(-6875 -225);
DISPLAY 0.617021 (-6875 -225);
PAINT RED (-6875 -225);
FORCEPROP 1 LAST PART_NUMBER G21497-005
J 2
(-6650 -175);
DISPLAY 0.617021 (-6650 -175);
PAINT BLUE (-6650 -175);
FORCEPROP 1 LASTPIN (-6900 -175) $PN 2
J 0
(-6938 -163);
DISPLAY 0.617021 (-6938 -163);
PAINT ORANGE (-6938 -163);
FORCEPROP 1 LAST TOLERANCE 5%
J 0
(-6950 -225);
DISPLAY 0.617021 (-6950 -225);
PAINT SKYBLUE (-6950 -225);
FORCEPROP 1 LASTPIN (-7100 -175) $PN 1
J 0
(-7088 -163);
DISPLAY 0.617021 (-7088 -163);
PAINT ORANGE (-7088 -163);
FORCEPROP 1 LAST VALUE 0.0
J 2
(-7025 -225);
DISPLAY 0.617021 (-7025 -225);
PAINT SKYBLUE (-7025 -225);
FORCEPROP 1 LAST WATTAGE 1/16W
J 2
(-7125 -225);
DISPLAY 0.617021 (-7125 -225);
PAINT SKYBLUE (-7125 -225);
FORCEPROP 1 LAST LOCATION R1C31
J 2
(-7125 -175);
DISPLAY 0.617021 (-7125 -175);
PAINT AQUA (-7125 -175);
FORCEPROP 2 LAST NO_XNET_CONNECTION 1
J 0
(-7050 25);
PAINT MONO (-7050 25);
DISPLAY INVISIBLE (-7050 25);
FORCEPROP 2 LAST SEC 1
J 0
(-7050 25);
DISPLAY 0.680851 (-7050 25);
PAINT MONO (-7050 25);
DISPLAY INVISIBLE (-7050 25);
FORCEPROP 2 LAST SEC_TYPE 0402
J 0
(-7050 25);
DISPLAY 1.021277 (-7050 25);
PAINT ORANGE (-7050 25);
DISPLAY INVISIBLE (-7050 25);
FORCEPROP 0 LAST ROOM IO_SLOT
J 0
(-6925 -75);
DISPLAY 1.021277 (-6925 -75);
PAINT ORANGE (-6925 -75);
DISPLAY INVISIBLE (-6925 -75);
FORCEPROP 2 LAST CDS_LIB mstr_discrete
J 0
(-7000 -175);
PAINT ORANGE (-7000 -175);
DISPLAY INVISIBLE (-7000 -175);
FORCEPROP 2 LAST CDS_LOCATION R1C31
J 2
(-7125 -175);
DISPLAY 0.617021 (-7125 -175);
PAINT AQUA (-7125 -175);
DISPLAY INVISIBLE (-7125 -175);
FORCEPROP 0 LAST CDS_SEC 1
J 0
(-6650 -125);
PAINT MONO (-6650 -125);
DISPLAY INVISIBLE (-6650 -125);
FORCEPROP 1 LAST PATH I6
J 0
(-7050 -25);
DISPLAY 0.978723 (-7050 -25);
PAINT WHITE (-7050 -25);
DISPLAY INVISIBLE (-7050 -25);
FORCEADD TAP..6
R 2
(-2175 1275);
FORCEPROP 3 LASTPIN (-2225 1275) SIG_NAME P3E_CPU1_PE3_MP_TXP<9>
J 0
(-2215 1285);
DISPLAY 0.659574 (-2215 1285);
PAINT MONO (-2215 1285);
DISPLAY INVISIBLE (-2215 1285);
FORCEPROP 1 LASTPIN (-2225 1275) BN 9
J 2
(-2173 1283);
DISPLAY 0.617021 (-2173 1283);
PAINT GREEN (-2173 1283);
FORCEPROP 2 LAST CDS_LIB mstr_standard
J 0
(-2175 1275);
PAINT ORANGE (-2175 1275);
DISPLAY INVISIBLE (-2175 1275);
FORCEPROP 1 LAST BODY_TYPE PLUMBING
J 2
(-2175 1225);
DISPLAY 1.234043 (-2175 1225);
PAINT GREEN (-2175 1225);
DISPLAY INVISIBLE (-2175 1225);
FORCEPROP 1 LAST HDL_TAP TRUE
J 2
(-2500 1150);
DISPLAY 1.234043 (-2500 1150);
PAINT GREEN (-2500 1150);
DISPLAY INVISIBLE (-2500 1150);
FORCEPROP 1 LAST PATH I60
J 2
(-2173 1275);
DISPLAY 0.872340 (-2173 1275);
PAINT GREEN (-2173 1275);
DISPLAY INVISIBLE (-2173 1275);
FORCEADD TAP..6
R 2
(-2175 1425);
FORCEPROP 3 LASTPIN (-2225 1425) SIG_NAME P3E_CPU1_PE3_MP_TXP<8>
J 0
(-2215 1435);
DISPLAY 0.659574 (-2215 1435);
PAINT MONO (-2215 1435);
DISPLAY INVISIBLE (-2215 1435);
FORCEPROP 1 LASTPIN (-2225 1425) BN 8
J 2
(-2173 1433);
DISPLAY 0.617021 (-2173 1433);
PAINT GREEN (-2173 1433);
FORCEPROP 2 LAST CDS_LIB mstr_standard
J 0
(-2175 1425);
PAINT ORANGE (-2175 1425);
DISPLAY INVISIBLE (-2175 1425);
FORCEPROP 1 LAST BODY_TYPE PLUMBING
J 2
(-2175 1375);
DISPLAY 1.234043 (-2175 1375);
PAINT GREEN (-2175 1375);
DISPLAY INVISIBLE (-2175 1375);
FORCEPROP 1 LAST HDL_TAP TRUE
J 2
(-2500 1300);
DISPLAY 1.234043 (-2500 1300);
PAINT GREEN (-2500 1300);
DISPLAY INVISIBLE (-2500 1300);
FORCEPROP 1 LAST PATH I61
J 2
(-2173 1425);
DISPLAY 0.872340 (-2173 1425);
PAINT GREEN (-2173 1425);
DISPLAY INVISIBLE (-2173 1425);
FORCEADD TAP..6
R 2
(-1925 1125);
FORCEPROP 3 LASTPIN (-1975 1125) SIG_NAME P3E_CPU1_PE3_MP_TXN<10>
J 0
(-1965 1135);
DISPLAY 0.659574 (-1965 1135);
PAINT MONO (-1965 1135);
DISPLAY INVISIBLE (-1965 1135);
FORCEPROP 1 LASTPIN (-1975 1125) BN 10
J 2
(-1923 1133);
DISPLAY 0.617021 (-1923 1133);
PAINT GREEN (-1923 1133);
FORCEPROP 2 LAST CDS_LIB mstr_standard
J 0
(-1925 1125);
PAINT ORANGE (-1925 1125);
DISPLAY INVISIBLE (-1925 1125);
FORCEPROP 1 LAST BODY_TYPE PLUMBING
J 2
(-1925 1075);
DISPLAY 1.234043 (-1925 1075);
PAINT GREEN (-1925 1075);
DISPLAY INVISIBLE (-1925 1075);
FORCEPROP 1 LAST HDL_TAP TRUE
J 2
(-2250 1000);
DISPLAY 1.234043 (-2250 1000);
PAINT GREEN (-2250 1000);
DISPLAY INVISIBLE (-2250 1000);
FORCEPROP 1 LAST PATH I62
J 2
(-1923 1125);
DISPLAY 0.872340 (-1923 1125);
PAINT GREEN (-1923 1125);
DISPLAY INVISIBLE (-1923 1125);
FORCEADD TAP..6
R 2
(-1925 1325);
FORCEPROP 3 LASTPIN (-1975 1325) SIG_NAME P3E_CPU1_PE3_MP_TXN<9>
J 0
(-1965 1335);
DISPLAY 0.659574 (-1965 1335);
PAINT MONO (-1965 1335);
DISPLAY INVISIBLE (-1965 1335);
FORCEPROP 1 LASTPIN (-1975 1325) BN 9
J 2
(-1923 1333);
DISPLAY 0.617021 (-1923 1333);
PAINT GREEN (-1923 1333);
FORCEPROP 2 LAST CDS_LIB mstr_standard
J 0
(-1925 1325);
PAINT ORANGE (-1925 1325);
DISPLAY INVISIBLE (-1925 1325);
FORCEPROP 1 LAST BODY_TYPE PLUMBING
J 2
(-1925 1275);
DISPLAY 1.234043 (-1925 1275);
PAINT GREEN (-1925 1275);
DISPLAY INVISIBLE (-1925 1275);
FORCEPROP 1 LAST HDL_TAP TRUE
J 2
(-2250 1200);
DISPLAY 1.234043 (-2250 1200);
PAINT GREEN (-2250 1200);
DISPLAY INVISIBLE (-2250 1200);
FORCEPROP 1 LAST PATH I63
J 2
(-1923 1325);
DISPLAY 0.872340 (-1923 1325);
PAINT GREEN (-1923 1325);
DISPLAY INVISIBLE (-1923 1325);
FORCEADD TAP..6
R 2
(-1925 1475);
FORCEPROP 3 LASTPIN (-1975 1475) SIG_NAME P3E_CPU1_PE3_MP_TXN<8>
J 0
(-1965 1485);
DISPLAY 0.659574 (-1965 1485);
PAINT MONO (-1965 1485);
DISPLAY INVISIBLE (-1965 1485);
FORCEPROP 1 LASTPIN (-1975 1475) BN 8
J 2
(-1923 1483);
DISPLAY 0.617021 (-1923 1483);
PAINT GREEN (-1923 1483);
FORCEPROP 2 LAST CDS_LIB mstr_standard
J 0
(-1925 1475);
PAINT ORANGE (-1925 1475);
DISPLAY INVISIBLE (-1925 1475);
FORCEPROP 1 LAST BODY_TYPE PLUMBING
J 2
(-1925 1425);
DISPLAY 1.234043 (-1925 1425);
PAINT GREEN (-1925 1425);
DISPLAY INVISIBLE (-1925 1425);
FORCEPROP 1 LAST HDL_TAP TRUE
J 2
(-2250 1350);
DISPLAY 1.234043 (-2250 1350);
PAINT GREEN (-2250 1350);
DISPLAY INVISIBLE (-2250 1350);
FORCEPROP 1 LAST PATH I64
J 2
(-1923 1475);
DISPLAY 0.872340 (-1923 1475);
PAINT GREEN (-1923 1475);
DISPLAY INVISIBLE (-1923 1475);
FORCEADD TAP..6
R 2
(-2175 1675);
FORCEPROP 3 LASTPIN (-2225 1675) SIG_NAME P3E_CPU1_PE3_MP_TXP<13>
J 0
(-2215 1685);
DISPLAY 0.659574 (-2215 1685);
PAINT MONO (-2215 1685);
DISPLAY INVISIBLE (-2215 1685);
FORCEPROP 1 LASTPIN (-2225 1675) BN 13
J 2
(-2173 1683);
DISPLAY 0.617021 (-2173 1683);
PAINT GREEN (-2173 1683);
FORCEPROP 2 LAST CDS_LIB mstr_standard
J 0
(-2175 1675);
PAINT ORANGE (-2175 1675);
DISPLAY INVISIBLE (-2175 1675);
FORCEPROP 1 LAST BODY_TYPE PLUMBING
J 2
(-2175 1625);
DISPLAY 1.234043 (-2175 1625);
PAINT GREEN (-2175 1625);
DISPLAY INVISIBLE (-2175 1625);
FORCEPROP 1 LAST HDL_TAP TRUE
J 2
(-2500 1550);
DISPLAY 1.234043 (-2500 1550);
PAINT GREEN (-2500 1550);
DISPLAY INVISIBLE (-2500 1550);
FORCEPROP 1 LAST PATH I65
J 2
(-2173 1675);
DISPLAY 0.872340 (-2173 1675);
PAINT GREEN (-2173 1675);
DISPLAY INVISIBLE (-2173 1675);
FORCEADD TAP..6
R 2
(-2175 1825);
FORCEPROP 3 LASTPIN (-2225 1825) SIG_NAME P3E_CPU1_PE3_MP_TXP<12>
J 0
(-2215 1835);
DISPLAY 0.659574 (-2215 1835);
PAINT MONO (-2215 1835);
DISPLAY INVISIBLE (-2215 1835);
FORCEPROP 1 LASTPIN (-2225 1825) BN 12
J 2
(-2173 1833);
DISPLAY 0.617021 (-2173 1833);
PAINT GREEN (-2173 1833);
FORCEPROP 2 LAST CDS_LIB mstr_standard
J 0
(-2175 1825);
PAINT ORANGE (-2175 1825);
DISPLAY INVISIBLE (-2175 1825);
FORCEPROP 1 LAST BODY_TYPE PLUMBING
J 2
(-2175 1775);
DISPLAY 1.234043 (-2175 1775);
PAINT GREEN (-2175 1775);
DISPLAY INVISIBLE (-2175 1775);
FORCEPROP 1 LAST HDL_TAP TRUE
J 2
(-2500 1700);
DISPLAY 1.234043 (-2500 1700);
PAINT GREEN (-2500 1700);
DISPLAY INVISIBLE (-2500 1700);
FORCEPROP 1 LAST PATH I66
J 2
(-2173 1825);
DISPLAY 0.872340 (-2173 1825);
PAINT GREEN (-2173 1825);
DISPLAY INVISIBLE (-2173 1825);
FORCEADD TAP..6
R 2
(-2175 1975);
FORCEPROP 3 LASTPIN (-2225 1975) SIG_NAME P3E_CPU1_PE3_MP_TXP<11>
J 0
(-2215 1985);
DISPLAY 0.659574 (-2215 1985);
PAINT MONO (-2215 1985);
DISPLAY INVISIBLE (-2215 1985);
FORCEPROP 1 LASTPIN (-2225 1975) BN 11
J 2
(-2173 1983);
DISPLAY 0.617021 (-2173 1983);
PAINT GREEN (-2173 1983);
FORCEPROP 2 LAST CDS_LIB mstr_standard
J 0
(-2175 1975);
PAINT ORANGE (-2175 1975);
DISPLAY INVISIBLE (-2175 1975);
FORCEPROP 1 LAST BODY_TYPE PLUMBING
J 2
(-2175 1925);
DISPLAY 1.234043 (-2175 1925);
PAINT GREEN (-2175 1925);
DISPLAY INVISIBLE (-2175 1925);
FORCEPROP 1 LAST HDL_TAP TRUE
J 2
(-2500 1850);
DISPLAY 1.234043 (-2500 1850);
PAINT GREEN (-2500 1850);
DISPLAY INVISIBLE (-2500 1850);
FORCEPROP 1 LAST PATH I67
J 2
(-2173 1975);
DISPLAY 0.872340 (-2173 1975);
PAINT GREEN (-2173 1975);
DISPLAY INVISIBLE (-2173 1975);
FORCEADD TAP..6
R 2
(-2175 2175);
FORCEPROP 3 LASTPIN (-2225 2175) SIG_NAME P3E_CPU1_PE3_MP_TXP<15>
J 0
(-2215 2185);
DISPLAY 0.659574 (-2215 2185);
PAINT MONO (-2215 2185);
DISPLAY INVISIBLE (-2215 2185);
FORCEPROP 1 LASTPIN (-2225 2175) BN 15
J 2
(-2173 2183);
DISPLAY 0.617021 (-2173 2183);
PAINT GREEN (-2173 2183);
FORCEPROP 2 LAST CDS_LIB mstr_standard
J 0
(-2175 2175);
PAINT ORANGE (-2175 2175);
DISPLAY INVISIBLE (-2175 2175);
FORCEPROP 1 LAST BODY_TYPE PLUMBING
J 2
(-2175 2125);
DISPLAY 1.234043 (-2175 2125);
PAINT GREEN (-2175 2125);
DISPLAY INVISIBLE (-2175 2125);
FORCEPROP 1 LAST HDL_TAP TRUE
J 2
(-2500 2050);
DISPLAY 1.234043 (-2500 2050);
PAINT GREEN (-2500 2050);
DISPLAY INVISIBLE (-2500 2050);
FORCEPROP 1 LAST PATH I68
J 2
(-2173 2175);
DISPLAY 0.872340 (-2173 2175);
PAINT GREEN (-2173 2175);
DISPLAY INVISIBLE (-2173 2175);
FORCEADD TAP..6
R 2
(-2175 2325);
FORCEPROP 3 LASTPIN (-2225 2325) SIG_NAME P3E_CPU1_PE3_MP_TXP<14>
J 0
(-2215 2335);
DISPLAY 0.659574 (-2215 2335);
PAINT MONO (-2215 2335);
DISPLAY INVISIBLE (-2215 2335);
FORCEPROP 1 LASTPIN (-2225 2325) BN 14
J 2
(-2173 2333);
DISPLAY 0.617021 (-2173 2333);
PAINT GREEN (-2173 2333);
FORCEPROP 2 LAST CDS_LIB mstr_standard
J 0
(-2175 2325);
PAINT ORANGE (-2175 2325);
DISPLAY INVISIBLE (-2175 2325);
FORCEPROP 1 LAST BODY_TYPE PLUMBING
J 2
(-2175 2275);
DISPLAY 1.234043 (-2175 2275);
PAINT GREEN (-2175 2275);
DISPLAY INVISIBLE (-2175 2275);
FORCEPROP 1 LAST HDL_TAP TRUE
J 2
(-2500 2200);
DISPLAY 1.234043 (-2500 2200);
PAINT GREEN (-2500 2200);
DISPLAY INVISIBLE (-2500 2200);
FORCEPROP 1 LAST PATH I69
J 2
(-2173 2325);
DISPLAY 0.872340 (-2173 2325);
PAINT GREEN (-2173 2325);
DISPLAY INVISIBLE (-2173 2325);
FORCEADD RES..1
(-7000 -25);
FORCEPROP 1 LAST PART_NUMBER G21497-005
J 2
(-6650 -25);
DISPLAY 0.617021 (-6650 -25);
PAINT BLUE (-6650 -25);
FORCEPROP 1 LASTPIN (-6900 -25) $PN 2
J 0
(-6938 -13);
DISPLAY 0.617021 (-6938 -13);
PAINT ORANGE (-6938 -13);
FORCEPROP 1 LASTPIN (-7100 -25) $PN 1
J 0
(-7088 -13);
DISPLAY 0.617021 (-7088 -13);
PAINT ORANGE (-7088 -13);
FORCEPROP 1 LAST PACK_TYPE 0402
J 0
(-6750 -75);
DISPLAY 0.617021 (-6750 -75);
PAINT SKYBLUE (-6750 -75);
FORCEPROP 1 LAST MATERIAL EMPTY
J 0
(-6875 -75);
DISPLAY 0.617021 (-6875 -75);
PAINT RED (-6875 -75);
FORCEPROP 1 LAST TOLERANCE 5%
J 0
(-6950 -75);
DISPLAY 0.617021 (-6950 -75);
PAINT SKYBLUE (-6950 -75);
FORCEPROP 1 LAST VALUE 0.0
J 2
(-7025 -75);
DISPLAY 0.617021 (-7025 -75);
PAINT SKYBLUE (-7025 -75);
FORCEPROP 1 LAST LOCATION R1F9
J 2
(-7125 -25);
DISPLAY 0.617021 (-7125 -25);
PAINT AQUA (-7125 -25);
FORCEPROP 1 LAST WATTAGE 1/16W
J 2
(-7125 -75);
DISPLAY 0.617021 (-7125 -75);
PAINT SKYBLUE (-7125 -75);
FORCEPROP 0 LAST ROOM IO_SLOT
J 0
(-6925 75);
DISPLAY 1.021277 (-6925 75);
PAINT ORANGE (-6925 75);
DISPLAY INVISIBLE (-6925 75);
FORCEPROP 2 LAST NO_XNET_CONNECTION 1
J 0
(-7050 175);
PAINT MONO (-7050 175);
DISPLAY INVISIBLE (-7050 175);
FORCEPROP 2 LAST SEC 1
J 0
(-7050 175);
DISPLAY 0.680851 (-7050 175);
PAINT MONO (-7050 175);
DISPLAY INVISIBLE (-7050 175);
FORCEPROP 2 LAST SEC_TYPE 0402
J 0
(-7050 175);
DISPLAY 1.021277 (-7050 175);
PAINT ORANGE (-7050 175);
DISPLAY INVISIBLE (-7050 175);
FORCEPROP 2 LAST CDS_LIB mstr_discrete
J 0
(-7000 -25);
PAINT ORANGE (-7000 -25);
DISPLAY INVISIBLE (-7000 -25);
FORCEPROP 2 LAST CDS_LOCATION R1F9
J 2
(-7125 -25);
DISPLAY 0.617021 (-7125 -25);
PAINT AQUA (-7125 -25);
DISPLAY INVISIBLE (-7125 -25);
FORCEPROP 0 LAST CDS_SEC 1
J 0
(-6650 25);
PAINT MONO (-6650 25);
DISPLAY INVISIBLE (-6650 25);
FORCEPROP 1 LAST PATH I7
J 0
(-7050 125);
DISPLAY 0.978723 (-7050 125);
PAINT WHITE (-7050 125);
DISPLAY INVISIBLE (-7050 125);
FORCEADD TAP..6
R 2
(-1925 1725);
FORCEPROP 3 LASTPIN (-1975 1725) SIG_NAME P3E_CPU1_PE3_MP_TXN<13>
J 0
(-1965 1735);
DISPLAY 0.659574 (-1965 1735);
PAINT MONO (-1965 1735);
DISPLAY INVISIBLE (-1965 1735);
FORCEPROP 1 LASTPIN (-1975 1725) BN 13
J 2
(-1950 1725);
DISPLAY 0.617021 (-1950 1725);
PAINT GREEN (-1950 1725);
FORCEPROP 2 LAST CDS_LIB mstr_standard
J 0
(-1925 1725);
PAINT ORANGE (-1925 1725);
DISPLAY INVISIBLE (-1925 1725);
FORCEPROP 1 LAST BODY_TYPE PLUMBING
J 2
(-1925 1675);
DISPLAY 1.234043 (-1925 1675);
PAINT GREEN (-1925 1675);
DISPLAY INVISIBLE (-1925 1675);
FORCEPROP 1 LAST HDL_TAP TRUE
J 2
(-2250 1600);
DISPLAY 1.234043 (-2250 1600);
PAINT GREEN (-2250 1600);
DISPLAY INVISIBLE (-2250 1600);
FORCEPROP 1 LAST PATH I70
J 2
(-1923 1725);
DISPLAY 0.872340 (-1923 1725);
PAINT GREEN (-1923 1725);
DISPLAY INVISIBLE (-1923 1725);
FORCEADD TAP..6
R 2
(-1925 1875);
FORCEPROP 3 LASTPIN (-1975 1875) SIG_NAME P3E_CPU1_PE3_MP_TXN<12>
J 0
(-1965 1885);
DISPLAY 0.659574 (-1965 1885);
PAINT MONO (-1965 1885);
DISPLAY INVISIBLE (-1965 1885);
FORCEPROP 1 LASTPIN (-1975 1875) BN 12
J 2
(-1923 1883);
DISPLAY 0.617021 (-1923 1883);
PAINT GREEN (-1923 1883);
FORCEPROP 2 LAST CDS_LIB mstr_standard
J 0
(-1925 1875);
PAINT ORANGE (-1925 1875);
DISPLAY INVISIBLE (-1925 1875);
FORCEPROP 1 LAST BODY_TYPE PLUMBING
J 2
(-1925 1825);
DISPLAY 1.234043 (-1925 1825);
PAINT GREEN (-1925 1825);
DISPLAY INVISIBLE (-1925 1825);
FORCEPROP 1 LAST HDL_TAP TRUE
J 2
(-2250 1750);
DISPLAY 1.234043 (-2250 1750);
PAINT GREEN (-2250 1750);
DISPLAY INVISIBLE (-2250 1750);
FORCEPROP 1 LAST PATH I71
J 2
(-1923 1875);
DISPLAY 0.872340 (-1923 1875);
PAINT GREEN (-1923 1875);
DISPLAY INVISIBLE (-1923 1875);
FORCEADD TAP..6
R 2
(-1925 2025);
FORCEPROP 3 LASTPIN (-1975 2025) SIG_NAME P3E_CPU1_PE3_MP_TXN<11>
J 0
(-1965 2035);
DISPLAY 0.659574 (-1965 2035);
PAINT MONO (-1965 2035);
DISPLAY INVISIBLE (-1965 2035);
FORCEPROP 1 LASTPIN (-1975 2025) BN 11
J 2
(-1923 2033);
DISPLAY 0.617021 (-1923 2033);
PAINT GREEN (-1923 2033);
FORCEPROP 2 LAST CDS_LIB mstr_standard
J 0
(-1925 2025);
PAINT ORANGE (-1925 2025);
DISPLAY INVISIBLE (-1925 2025);
FORCEPROP 1 LAST BODY_TYPE PLUMBING
J 2
(-1925 1975);
DISPLAY 1.234043 (-1925 1975);
PAINT GREEN (-1925 1975);
DISPLAY INVISIBLE (-1925 1975);
FORCEPROP 1 LAST HDL_TAP TRUE
J 2
(-2250 1900);
DISPLAY 1.234043 (-2250 1900);
PAINT GREEN (-2250 1900);
DISPLAY INVISIBLE (-2250 1900);
FORCEPROP 1 LAST PATH I72
J 2
(-1923 2025);
DISPLAY 0.872340 (-1923 2025);
PAINT GREEN (-1923 2025);
DISPLAY INVISIBLE (-1923 2025);
FORCEADD TAP..6
R 2
(-1925 2225);
FORCEPROP 3 LASTPIN (-1975 2225) SIG_NAME P3E_CPU1_PE3_MP_TXN<15>
J 0
(-1965 2235);
DISPLAY 0.659574 (-1965 2235);
PAINT MONO (-1965 2235);
DISPLAY INVISIBLE (-1965 2235);
FORCEPROP 1 LASTPIN (-1975 2225) BN 15
J 2
(-1923 2233);
DISPLAY 0.617021 (-1923 2233);
PAINT GREEN (-1923 2233);
FORCEPROP 2 LAST CDS_LIB mstr_standard
J 0
(-1925 2225);
PAINT ORANGE (-1925 2225);
DISPLAY INVISIBLE (-1925 2225);
FORCEPROP 1 LAST BODY_TYPE PLUMBING
J 2
(-1925 2175);
DISPLAY 1.234043 (-1925 2175);
PAINT GREEN (-1925 2175);
DISPLAY INVISIBLE (-1925 2175);
FORCEPROP 1 LAST HDL_TAP TRUE
J 2
(-2250 2100);
DISPLAY 1.234043 (-2250 2100);
PAINT GREEN (-2250 2100);
DISPLAY INVISIBLE (-2250 2100);
FORCEPROP 1 LAST PATH I73
J 2
(-1923 2225);
DISPLAY 0.872340 (-1923 2225);
PAINT GREEN (-1923 2225);
DISPLAY INVISIBLE (-1923 2225);
FORCEADD TAP..6
R 2
(-1925 2375);
FORCEPROP 3 LASTPIN (-1975 2375) SIG_NAME P3E_CPU1_PE3_MP_TXN<14>
J 0
(-1965 2385);
DISPLAY 0.659574 (-1965 2385);
PAINT MONO (-1965 2385);
DISPLAY INVISIBLE (-1965 2385);
FORCEPROP 1 LASTPIN (-1975 2375) BN 14
J 2
(-1923 2383);
DISPLAY 0.617021 (-1923 2383);
PAINT GREEN (-1923 2383);
FORCEPROP 2 LAST CDS_LIB mstr_standard
J 0
(-1925 2375);
PAINT ORANGE (-1925 2375);
DISPLAY INVISIBLE (-1925 2375);
FORCEPROP 1 LAST BODY_TYPE PLUMBING
J 2
(-1925 2325);
DISPLAY 1.234043 (-1925 2325);
PAINT GREEN (-1925 2325);
DISPLAY INVISIBLE (-1925 2325);
FORCEPROP 1 LAST HDL_TAP TRUE
J 2
(-2250 2250);
DISPLAY 1.234043 (-2250 2250);
PAINT GREEN (-2250 2250);
DISPLAY INVISIBLE (-2250 2250);
FORCEPROP 1 LAST PATH I74
J 2
(-1923 2375);
DISPLAY 0.872340 (-1923 2375);
PAINT GREEN (-1923 2375);
DISPLAY INVISIBLE (-1923 2375);
FORCEADD OFFPAGE..1
R 2
(-1050 3050);
FORCEPROP 2 LAST $XR0 66 
J 0
(-864 3050);
DISPLAY 0.638298 (-864 3050);
PAINT MONO (-864 3050);
FORCEPROP 2 LAST CDS_LIB mstr_standard
J 0
(-1050 3050);
PAINT ORANGE (-1050 3050);
DISPLAY INVISIBLE (-1050 3050);
FORCEPROP 1 LAST OFFPAGE TRUE
J 2
(-1375 2925);
DISPLAY 0.872340 (-1375 2925);
PAINT GREEN (-1375 2925);
DISPLAY INVISIBLE (-1375 2925);
FORCEPROP 1 LAST COMMENT_BODY TRUE
J 2
(-1175 2950);
DISPLAY 0.872340 (-1175 2950);
PAINT GREEN (-1175 2950);
DISPLAY INVISIBLE (-1175 2950);
FORCEPROP 2 LAST PATH I75
J 0
(-850 3100);
DISPLAY 1.021277 (-850 3100);
PAINT ORANGE (-850 3100);
DISPLAY INVISIBLE (-850 3100);
FORCEADD OFFPAGE..1
R 2
(-1050 3150);
FORCEPROP 2 LAST $XR0 66 
J 0
(-864 3150);
DISPLAY 0.638298 (-864 3150);
PAINT MONO (-864 3150);
FORCEPROP 2 LAST CDS_LIB mstr_standard
J 0
(-1050 3150);
PAINT ORANGE (-1050 3150);
DISPLAY INVISIBLE (-1050 3150);
FORCEPROP 1 LAST OFFPAGE TRUE
J 2
(-1375 3025);
DISPLAY 0.872340 (-1375 3025);
PAINT GREEN (-1375 3025);
DISPLAY INVISIBLE (-1375 3025);
FORCEPROP 1 LAST COMMENT_BODY TRUE
J 2
(-1175 3050);
DISPLAY 0.872340 (-1175 3050);
PAINT GREEN (-1175 3050);
DISPLAY INVISIBLE (-1175 3050);
FORCEPROP 2 LAST PATH I76
J 0
(-850 3200);
DISPLAY 1.021277 (-850 3200);
PAINT ORANGE (-850 3200);
DISPLAY INVISIBLE (-850 3200);
FORCEADD TAP..1
R 2
(-6350 2525);
FORCEPROP 3 LASTPIN (-6300 2525) SIG_NAME P3E_CPU1_PE3_MP_RXN<11>
J 0
(-6290 2535);
DISPLAY 0.659574 (-6290 2535);
PAINT MONO (-6290 2535);
DISPLAY INVISIBLE (-6290 2535);
FORCEPROP 1 LASTPIN (-6300 2525) BN 11
J 2
(-6288 2533);
DISPLAY 0.617021 (-6288 2533);
PAINT GREEN (-6288 2533);
FORCEPROP 1 LAST BODY_TYPE PLUMBING
J 2
(-6350 2575);
DISPLAY 1.446809 (-6350 2575);
PAINT GREEN (-6350 2575);
DISPLAY INVISIBLE (-6350 2575);
FORCEPROP 2 LAST CDS_LIB mstr_standard
J 0
(-6350 2525);
PAINT MONO (-6350 2525);
DISPLAY INVISIBLE (-6350 2525);
FORCEPROP 1 LAST HDL_TAP TRUE
J 2
(-6675 2400);
DISPLAY 1.446809 (-6675 2400);
PAINT GREEN (-6675 2400);
DISPLAY INVISIBLE (-6675 2400);
FORCEPROP 1 LAST PATH I77
J 2
(-6348 2525);
DISPLAY 0.872340 (-6348 2525);
PAINT GREEN (-6348 2525);
DISPLAY INVISIBLE (-6348 2525);
FORCEADD DM-FCI-CONN76-8R-GP-U-01..1
(-5000 2050);
FORCEPROP 0 LAST CONFIG H22707-001
J 0
(-5554 3549);
DISPLAY 1.021277 (-5554 3549);
PAINT BROWN (-5554 3549);
DISPLAY BOTH (-5554 3549);
FORCEPROP 0 LAST NEW_PN 20.82092.076
J 0
(-5559 3467);
DISPLAY 1.021277 (-5559 3467);
PAINT BROWN (-5559 3467);
DISPLAY BOTH (-5559 3467);
FORCEPROP 2 LASTPIN (-4375 1225) $PN G8
J 0
(-4365 1235);
DISPLAY 0.808511 (-4365 1235);
PAINT ORANGE (-4365 1235);
FORCEPROP 2 LASTPIN (-4375 2025) $PN A7
J 0
(-4365 2035);
DISPLAY 0.808511 (-4365 2035);
PAINT ORANGE (-4365 2035);
FORCEPROP 2 LASTPIN (-4375 2775) $PN G5
J 0
(-4365 2785);
DISPLAY 0.808511 (-4365 2785);
PAINT ORANGE (-4365 2785);
FORCEPROP 2 LASTPIN (-4375 2725) $PN H5
J 0
(-4365 2735);
DISPLAY 0.808511 (-4365 2735);
PAINT ORANGE (-4365 2735);
FORCEPROP 2 LASTPIN (-4375 2675) $PN I5
J 0
(-4365 2685);
DISPLAY 0.808511 (-4365 2685);
PAINT ORANGE (-4365 2685);
FORCEPROP 2 LASTPIN (-5625 1125) $PN I4
J 2
(-5635 1135);
DISPLAY 0.808511 (-5635 1135);
PAINT ORANGE (-5635 1135);
FORCEPROP 2 LASTPIN (-5625 1075) $PN J4
J 2
(-5635 1085);
DISPLAY 0.808511 (-5635 1085);
PAINT ORANGE (-5635 1085);
FORCEPROP 2 LASTPIN (-5625 1175) $PN H4
J 2
(-5635 1185);
DISPLAY 0.808511 (-5635 1185);
PAINT ORANGE (-5635 1185);
FORCEPROP 2 LASTPIN (-5625 1225) $PN G4
J 2
(-5635 1235);
DISPLAY 0.808511 (-5635 1235);
PAINT ORANGE (-5635 1235);
FORCEPROP 2 LASTPIN (-5625 1275) $PN F4
J 2
(-5635 1285);
DISPLAY 0.808511 (-5635 1285);
PAINT ORANGE (-5635 1285);
FORCEPROP 2 LASTPIN (-5625 1425) $PN C4
J 2
(-5635 1435);
DISPLAY 0.808511 (-5635 1435);
PAINT ORANGE (-5635 1435);
FORCEPROP 2 LASTPIN (-5625 1325) $PN E4
J 2
(-5635 1335);
DISPLAY 0.808511 (-5635 1335);
PAINT ORANGE (-5635 1335);
FORCEPROP 2 LASTPIN (-5625 1375) $PN D4
J 2
(-5635 1385);
DISPLAY 0.808511 (-5635 1385);
PAINT ORANGE (-5635 1385);
FORCEPROP 2 LASTPIN (-5625 1475) $PN B4
J 2
(-5635 1485);
DISPLAY 0.808511 (-5635 1485);
PAINT ORANGE (-5635 1485);
FORCEPROP 2 LASTPIN (-5625 1525) $PN A4
J 2
(-5635 1535);
DISPLAY 0.808511 (-5635 1535);
PAINT ORANGE (-5635 1535);
FORCEPROP 2 LASTPIN (-5625 1625) $PN I3
J 2
(-5635 1635);
DISPLAY 0.808511 (-5635 1635);
PAINT ORANGE (-5635 1635);
FORCEPROP 2 LASTPIN (-5625 1675) $PN H3
J 2
(-5635 1685);
DISPLAY 0.808511 (-5635 1685);
PAINT ORANGE (-5635 1685);
FORCEPROP 2 LASTPIN (-5625 1775) $PN F3
J 2
(-5635 1785);
DISPLAY 0.808511 (-5635 1785);
PAINT ORANGE (-5635 1785);
FORCEPROP 2 LASTPIN (-5625 1725) $PN G3
J 2
(-5635 1735);
DISPLAY 0.808511 (-5635 1735);
PAINT ORANGE (-5635 1735);
FORCEPROP 2 LASTPIN (-5625 1825) $PN E3
J 2
(-5635 1835);
DISPLAY 0.808511 (-5635 1835);
PAINT ORANGE (-5635 1835);
FORCEPROP 2 LASTPIN (-5625 1925) $PN C3
J 2
(-5635 1935);
DISPLAY 0.808511 (-5635 1935);
PAINT ORANGE (-5635 1935);
FORCEPROP 2 LASTPIN (-5625 1875) $PN D3
J 2
(-5635 1885);
DISPLAY 0.808511 (-5635 1885);
PAINT ORANGE (-5635 1885);
FORCEPROP 2 LASTPIN (-5625 1975) $PN B3
J 2
(-5635 1985);
DISPLAY 0.808511 (-5635 1985);
PAINT ORANGE (-5635 1985);
FORCEPROP 2 LASTPIN (-5625 2025) $PN A3
J 2
(-5635 2035);
DISPLAY 0.808511 (-5635 2035);
PAINT ORANGE (-5635 2035);
FORCEPROP 2 LASTPIN (-5625 2125) $PN J2
J 2
(-5635 2135);
DISPLAY 0.808511 (-5635 2135);
PAINT ORANGE (-5635 2135);
FORCEPROP 2 LASTPIN (-5625 2175) $PN I2
J 2
(-5635 2185);
DISPLAY 0.808511 (-5635 2185);
PAINT ORANGE (-5635 2185);
FORCEPROP 2 LASTPIN (-5625 2325) $PN F2
J 2
(-5635 2335);
DISPLAY 0.808511 (-5635 2335);
PAINT ORANGE (-5635 2335);
FORCEPROP 2 LASTPIN (-5625 2225) $PN H2
J 2
(-5635 2235);
DISPLAY 0.808511 (-5635 2235);
PAINT ORANGE (-5635 2235);
FORCEPROP 2 LASTPIN (-5625 2275) $PN G2
J 2
(-5635 2285);
DISPLAY 0.808511 (-5635 2285);
PAINT ORANGE (-5635 2285);
FORCEPROP 2 LASTPIN (-5625 2425) $PN D2
J 2
(-5635 2435);
DISPLAY 0.808511 (-5635 2435);
PAINT ORANGE (-5635 2435);
FORCEPROP 2 LASTPIN (-5625 2375) $PN E2
J 2
(-5635 2385);
DISPLAY 0.808511 (-5635 2385);
PAINT ORANGE (-5635 2385);
FORCEPROP 2 LASTPIN (-5625 2575) $PN A2
J 2
(-5635 2585);
DISPLAY 0.808511 (-5635 2585);
PAINT ORANGE (-5635 2585);
FORCEPROP 2 LASTPIN (-5625 2525) $PN B2
J 2
(-5635 2535);
DISPLAY 0.808511 (-5635 2535);
PAINT ORANGE (-5635 2535);
FORCEPROP 2 LASTPIN (-5625 2675) $PN I1
J 2
(-5635 2685);
DISPLAY 0.808511 (-5635 2685);
PAINT ORANGE (-5635 2685);
FORCEPROP 2 LASTPIN (-5625 2725) $PN H1
J 2
(-5635 2735);
DISPLAY 0.808511 (-5635 2735);
PAINT ORANGE (-5635 2735);
FORCEPROP 2 LASTPIN (-5625 2775) $PN G1
J 2
(-5635 2785);
DISPLAY 0.808511 (-5635 2785);
PAINT ORANGE (-5635 2785);
FORCEPROP 2 LASTPIN (-5625 2825) $PN F1
J 2
(-5635 2835);
DISPLAY 0.808511 (-5635 2835);
PAINT ORANGE (-5635 2835);
FORCEPROP 2 LASTPIN (-5625 2925) $PN D1
J 2
(-5635 2935);
DISPLAY 0.808511 (-5635 2935);
PAINT ORANGE (-5635 2935);
FORCEPROP 2 LASTPIN (-5625 2875) $PN E1
J 2
(-5635 2885);
DISPLAY 0.808511 (-5635 2885);
PAINT ORANGE (-5635 2885);
FORCEPROP 2 LASTPIN (-5625 2975) $PN C1
J 2
(-5635 2985);
DISPLAY 0.808511 (-5635 2985);
PAINT ORANGE (-5635 2985);
FORCEPROP 2 LASTPIN (-5625 3025) $PN B1
J 2
(-5635 3035);
DISPLAY 0.808511 (-5635 3035);
PAINT ORANGE (-5635 3035);
FORCEPROP 2 LASTPIN (-5625 3075) $PN A1
J 2
(-5635 3085);
DISPLAY 0.808511 (-5635 3085);
PAINT ORANGE (-5635 3085);
FORCEPROP 2 LASTPIN (-4375 1075) $PN J8
J 0
(-4365 1085);
DISPLAY 0.808511 (-4365 1085);
PAINT ORANGE (-4365 1085);
FORCEPROP 2 LASTPIN (-4375 1125) $PN I8
J 0
(-4365 1135);
DISPLAY 0.808511 (-4365 1135);
PAINT ORANGE (-4365 1135);
FORCEPROP 2 LASTPIN (-4375 1175) $PN H8
J 0
(-4365 1185);
DISPLAY 0.808511 (-4365 1185);
PAINT ORANGE (-4365 1185);
FORCEPROP 2 LASTPIN (-4375 1275) $PN F8
J 0
(-4365 1285);
DISPLAY 0.808511 (-4365 1285);
PAINT ORANGE (-4365 1285);
FORCEPROP 2 LASTPIN (-4375 1375) $PN D8
J 0
(-4365 1385);
DISPLAY 0.808511 (-4365 1385);
PAINT ORANGE (-4365 1385);
FORCEPROP 2 LASTPIN (-4375 1325) $PN E8
J 0
(-4365 1335);
DISPLAY 0.808511 (-4365 1335);
PAINT ORANGE (-4365 1335);
FORCEPROP 2 LASTPIN (-4375 1425) $PN C8
J 0
(-4365 1435);
DISPLAY 0.808511 (-4365 1435);
PAINT ORANGE (-4365 1435);
FORCEPROP 2 LASTPIN (-4375 1525) $PN A8
J 0
(-4365 1535);
DISPLAY 0.808511 (-4365 1535);
PAINT ORANGE (-4365 1535);
FORCEPROP 2 LASTPIN (-4375 1475) $PN B8
J 0
(-4365 1485);
DISPLAY 0.808511 (-4365 1485);
PAINT ORANGE (-4365 1485);
FORCEPROP 2 LASTPIN (-4375 1675) $PN H7
J 0
(-4365 1685);
DISPLAY 0.808511 (-4365 1685);
PAINT ORANGE (-4365 1685);
FORCEPROP 2 LASTPIN (-4375 1625) $PN I7
J 0
(-4365 1635);
DISPLAY 0.808511 (-4365 1635);
PAINT ORANGE (-4365 1635);
FORCEPROP 2 LASTPIN (-4375 1775) $PN F7
J 0
(-4365 1785);
DISPLAY 0.808511 (-4365 1785);
PAINT ORANGE (-4365 1785);
FORCEPROP 2 LASTPIN (-4375 1725) $PN G7
J 0
(-4365 1735);
DISPLAY 0.808511 (-4365 1735);
PAINT ORANGE (-4365 1735);
FORCEPROP 2 LASTPIN (-4375 1825) $PN E7
J 0
(-4365 1835);
DISPLAY 0.808511 (-4365 1835);
PAINT ORANGE (-4365 1835);
FORCEPROP 2 LASTPIN (-4375 1925) $PN C7
J 0
(-4365 1935);
DISPLAY 0.808511 (-4365 1935);
PAINT ORANGE (-4365 1935);
FORCEPROP 2 LASTPIN (-4375 1875) $PN D7
J 0
(-4365 1885);
DISPLAY 0.808511 (-4365 1885);
PAINT ORANGE (-4365 1885);
FORCEPROP 2 LASTPIN (-4375 1975) $PN B7
J 0
(-4365 1985);
DISPLAY 0.808511 (-4365 1985);
PAINT ORANGE (-4365 1985);
FORCEPROP 2 LASTPIN (-4375 2175) $PN I6
J 0
(-4365 2185);
DISPLAY 0.808511 (-4365 2185);
PAINT ORANGE (-4365 2185);
FORCEPROP 2 LASTPIN (-4375 2125) $PN J6
J 0
(-4365 2135);
DISPLAY 0.808511 (-4365 2135);
PAINT ORANGE (-4365 2135);
FORCEPROP 2 LASTPIN (-4375 2225) $PN H6
J 0
(-4365 2235);
DISPLAY 0.808511 (-4365 2235);
PAINT ORANGE (-4365 2235);
FORCEPROP 2 LASTPIN (-4375 2275) $PN G6
J 0
(-4365 2285);
DISPLAY 0.808511 (-4365 2285);
PAINT ORANGE (-4365 2285);
FORCEPROP 2 LASTPIN (-4375 2325) $PN F6
J 0
(-4365 2335);
DISPLAY 0.808511 (-4365 2335);
PAINT ORANGE (-4365 2335);
FORCEPROP 2 LASTPIN (-4375 2425) $PN D6
J 0
(-4365 2435);
DISPLAY 0.808511 (-4365 2435);
PAINT ORANGE (-4365 2435);
FORCEPROP 2 LASTPIN (-4375 2375) $PN E6
J 0
(-4365 2385);
DISPLAY 0.808511 (-4365 2385);
PAINT ORANGE (-4365 2385);
FORCEPROP 2 LASTPIN (-4375 2475) $PN C6
J 0
(-4365 2485);
DISPLAY 0.808511 (-4365 2485);
PAINT ORANGE (-4365 2485);
FORCEPROP 2 LASTPIN (-4375 2525) $PN B6
J 0
(-4365 2535);
DISPLAY 0.808511 (-4365 2535);
PAINT ORANGE (-4365 2535);
FORCEPROP 2 LASTPIN (-4375 2925) $PN D5
J 0
(-4365 2935);
DISPLAY 0.808511 (-4365 2935);
PAINT ORANGE (-4365 2935);
FORCEPROP 2 LASTPIN (-4375 2875) $PN E5
J 0
(-4365 2885);
DISPLAY 0.808511 (-4365 2885);
PAINT ORANGE (-4365 2885);
FORCEPROP 2 LASTPIN (-4375 2975) $PN C5
J 0
(-4365 2985);
DISPLAY 0.808511 (-4365 2985);
PAINT ORANGE (-4365 2985);
FORCEPROP 2 LASTPIN (-4375 2825) $PN F5
J 0
(-4365 2835);
DISPLAY 0.808511 (-4365 2835);
PAINT ORANGE (-4365 2835);
FORCEPROP 2 LASTPIN (-5625 2475) $PN C2
J 2
(-5635 2485);
DISPLAY 0.808511 (-5635 2485);
PAINT ORANGE (-5635 2485);
FORCEPROP 2 LASTPIN (-4375 2575) $PN A6
J 0
(-4365 2585);
DISPLAY 0.808511 (-4365 2585);
PAINT ORANGE (-4365 2585);
FORCEPROP 1 LAST LOCATION J1C1
J 0
(-5475 3300);
DISPLAY 0.617021 (-5475 3300);
PAINT GREEN (-5475 3300);
FORCEPROP 1 LAST VALUE DM-FCI-CONN76-8R-GP-U-01
J 0
(-5450 775);
DISPLAY 0.617021 (-5450 775);
PAINT GREEN (-5450 775);
FORCEPROP 2 LASTPIN (-4375 3025) $PN B5
J 0
(-4365 3035);
DISPLAY 0.808511 (-4365 3035);
PAINT ORANGE (-4365 3035);
FORCEPROP 2 LASTPIN (-4375 3075) $PN A5
J 0
(-4365 3085);
DISPLAY 0.808511 (-4365 3085);
PAINT ORANGE (-4365 3085);
FORCEPROP 1 LAST PACK_TYPE CONN-G4
J 0
(-5000 2050);
DISPLAY 0.617021 (-5000 2050);
PAINT GREEN (-5000 2050);
DISPLAY INVISIBLE (-5000 2050);
FORCEPROP 2 LAST SEC 1
J 0
(-5475 3350);
DISPLAY 0.680851 (-5475 3350);
PAINT MONO (-5475 3350);
DISPLAY INVISIBLE (-5475 3350);
FORCEPROP 2 LAST SEC_TYPE CONN-G4
J 0
(-5475 3350);
DISPLAY 1.021277 (-5475 3350);
PAINT ORANGE (-5475 3350);
DISPLAY INVISIBLE (-5475 3350);
FORCEPROP 1 LAST PART_NUMBER ZZ.82092.07601
J 0
(-5000 2010);
DISPLAY 0.617021 (-5000 2010);
PAINT GREEN (-5000 2010);
DISPLAY INVISIBLE (-5000 2010);
FORCEPROP 2 LAST CDS_LIB w_hdl
J 0
(-5000 2050);
PAINT MONO (-5000 2050);
DISPLAY INVISIBLE (-5000 2050);
FORCEPROP 1 LAST CDS_LMAN_SYM_OUTLINE -475,1225,475,-1225
J 0
(-5000 2050);
DISPLAY 0.468085 (-5000 2050);
PAINT GREEN (-5000 2050);
DISPLAY INVISIBLE (-5000 2050);
FORCEPROP 1 LAST PATH I79
J 0
(-5000 2090);
DISPLAY 0.617021 (-5000 2090);
PAINT GREEN (-5000 2090);
DISPLAY INVISIBLE (-5000 2090);
FORCEADD RES..1
(-7000 100);
FORCEPROP 1 LAST PACK_TYPE 0402
J 0
(-6750 50);
DISPLAY 0.617021 (-6750 50);
PAINT SKYBLUE (-6750 50);
FORCEPROP 1 LAST MATERIAL EMPTY
J 0
(-6875 50);
DISPLAY 0.617021 (-6875 50);
PAINT RED (-6875 50);
FORCEPROP 1 LASTPIN (-6900 100) $PN 2
J 0
(-6938 112);
DISPLAY 0.617021 (-6938 112);
PAINT ORANGE (-6938 112);
FORCEPROP 1 LAST TOLERANCE 5%
J 0
(-6950 50);
DISPLAY 0.617021 (-6950 50);
PAINT SKYBLUE (-6950 50);
FORCEPROP 1 LASTPIN (-7100 100) $PN 1
J 0
(-7088 112);
DISPLAY 0.617021 (-7088 112);
PAINT ORANGE (-7088 112);
FORCEPROP 1 LAST VALUE 0.0
J 2
(-7025 50);
DISPLAY 0.617021 (-7025 50);
PAINT SKYBLUE (-7025 50);
FORCEPROP 1 LAST WATTAGE 1/16W
J 2
(-7125 50);
DISPLAY 0.617021 (-7125 50);
PAINT SKYBLUE (-7125 50);
FORCEPROP 1 LAST LOCATION R1C9
J 2
(-7125 100);
DISPLAY 0.617021 (-7125 100);
PAINT AQUA (-7125 100);
FORCEPROP 1 LAST PART_NUMBER G21497-005
J 2
(-6650 100);
DISPLAY 0.617021 (-6650 100);
PAINT BLUE (-6650 100);
FORCEPROP 2 LAST NO_XNET_CONNECTION 1
J 0
(-7050 300);
PAINT MONO (-7050 300);
DISPLAY INVISIBLE (-7050 300);
FORCEPROP 2 LAST SEC 1
J 0
(-7050 300);
DISPLAY 0.680851 (-7050 300);
PAINT MONO (-7050 300);
DISPLAY INVISIBLE (-7050 300);
FORCEPROP 2 LAST SEC_TYPE 0402
J 0
(-7050 300);
DISPLAY 1.021277 (-7050 300);
PAINT ORANGE (-7050 300);
DISPLAY INVISIBLE (-7050 300);
FORCEPROP 0 LAST ROOM IO_SLOT
J 0
(-6925 200);
DISPLAY 1.021277 (-6925 200);
PAINT ORANGE (-6925 200);
DISPLAY INVISIBLE (-6925 200);
FORCEPROP 2 LAST CDS_LIB mstr_discrete
J 0
(-7000 100);
PAINT ORANGE (-7000 100);
DISPLAY INVISIBLE (-7000 100);
FORCEPROP 2 LAST CDS_LOCATION R1C9
J 2
(-7125 100);
DISPLAY 0.617021 (-7125 100);
PAINT AQUA (-7125 100);
DISPLAY INVISIBLE (-7125 100);
FORCEPROP 0 LAST CDS_SEC 1
J 0
(-6650 150);
PAINT MONO (-6650 150);
DISPLAY INVISIBLE (-6650 150);
FORCEPROP 1 LAST PATH I8
J 0
(-7050 250);
DISPLAY 0.978723 (-7050 250);
PAINT WHITE (-7050 250);
DISPLAY INVISIBLE (-7050 250);
FORCEADD RES..1
(-7000 225);
FORCEPROP 1 LAST PACK_TYPE 0402
J 0
(-6750 175);
DISPLAY 0.617021 (-6750 175);
PAINT SKYBLUE (-6750 175);
FORCEPROP 1 LAST MATERIAL EMPTY
J 0
(-6875 175);
DISPLAY 0.617021 (-6875 175);
PAINT RED (-6875 175);
FORCEPROP 1 LAST PART_NUMBER G21497-005
J 2
(-6650 225);
DISPLAY 0.617021 (-6650 225);
PAINT BLUE (-6650 225);
FORCEPROP 1 LASTPIN (-6900 225) $PN 2
J 0
(-6938 237);
DISPLAY 0.617021 (-6938 237);
PAINT ORANGE (-6938 237);
FORCEPROP 1 LASTPIN (-7100 225) $PN 1
J 0
(-7088 237);
DISPLAY 0.617021 (-7088 237);
PAINT ORANGE (-7088 237);
FORCEPROP 1 LAST TOLERANCE 5%
J 0
(-6950 175);
DISPLAY 0.617021 (-6950 175);
PAINT SKYBLUE (-6950 175);
FORCEPROP 1 LAST VALUE 0.0
J 2
(-7025 175);
DISPLAY 0.617021 (-7025 175);
PAINT SKYBLUE (-7025 175);
FORCEPROP 1 LAST LOCATION R1C10
J 2
(-7125 225);
DISPLAY 0.617021 (-7125 225);
PAINT AQUA (-7125 225);
FORCEPROP 1 LAST WATTAGE 1/16W
J 2
(-7125 175);
DISPLAY 0.617021 (-7125 175);
PAINT SKYBLUE (-7125 175);
FORCEPROP 0 LAST ROOM IO_SLOT
J 0
(-6925 325);
DISPLAY 1.021277 (-6925 325);
PAINT ORANGE (-6925 325);
DISPLAY INVISIBLE (-6925 325);
FORCEPROP 2 LAST SEC_TYPE 0402
J 0
(-7050 425);
DISPLAY 1.021277 (-7050 425);
PAINT ORANGE (-7050 425);
DISPLAY INVISIBLE (-7050 425);
FORCEPROP 2 LAST SEC 1
J 0
(-7050 425);
DISPLAY 0.680851 (-7050 425);
PAINT MONO (-7050 425);
DISPLAY INVISIBLE (-7050 425);
FORCEPROP 2 LAST NO_XNET_CONNECTION 1
J 0
(-7050 425);
PAINT MONO (-7050 425);
DISPLAY INVISIBLE (-7050 425);
FORCEPROP 2 LAST CDS_LIB mstr_discrete
J 0
(-7000 225);
PAINT ORANGE (-7000 225);
DISPLAY INVISIBLE (-7000 225);
FORCEPROP 2 LAST CDS_LOCATION R1C10
J 2
(-7125 225);
DISPLAY 0.617021 (-7125 225);
PAINT AQUA (-7125 225);
DISPLAY INVISIBLE (-7125 225);
FORCEPROP 0 LAST CDS_SEC 1
J 0
(-6650 275);
PAINT MONO (-6650 275);
DISPLAY INVISIBLE (-6650 275);
FORCEPROP 1 LAST PATH I9
J 0
(-7050 375);
DISPLAY 0.978723 (-7050 375);
PAINT WHITE (-7050 375);
DISPLAY INVISIBLE (-7050 375);
FORCEADD DESIGN_NOTE..1
(-7875 825);
FORCEPROP 0 LAST L4 WHEN USING WITH BULLDOG CREEK, POPULATE
J 0
(-8075 550);
DISPLAY 1.021277 (-8075 550);
PAINT ORANGE (-8075 550);
FORCEPROP 0 LAST L1 THESE RESISTORS USED TO STEER SIGNALS
J 0
(-8075 700);
DISPLAY 1.021277 (-8075 700);
PAINT ORANGE (-8075 700);
FORCEPROP 0 LAST L3 CREEK COMPATABILITY
J 0
(-8075 600);
DISPLAY 1.021277 (-8075 600);
PAINT ORANGE (-8075 600);
FORCEPROP 0 LAST L5 THESE RESISTORS
J 0
(-8075 500);
DISPLAY 1.021277 (-8075 500);
PAINT ORANGE (-8075 500);
FORCEPROP 0 LAST L2 FROM AIRMAX B TO AIRMAX A FOR BULLDOG
J 0
(-8075 650);
DISPLAY 1.021277 (-8075 650);
PAINT ORANGE (-8075 650);
FORCEPROP 2 LAST CDS_LIB mstr_symbols
J 0
(-7875 825);
PAINT ORANGE (-7875 825);
DISPLAY INVISIBLE (-7875 825);
FORCEPROP 1 LAST COMMENT_BODY TRUE
J 0
(-7850 925);
DISPLAY 0.978723 (-7850 925);
PAINT ORANGE (-7850 925);
DISPLAY INVISIBLE (-7850 925);
FORCEADD DNS..2
(-6995 -180);
PAINT RED (-6995 -180);
FORCEPROP 2 LAST CDS_LIB mstr_misc
J 0
(-6995 -180);
PAINT ORANGE (-6995 -180);
DISPLAY INVISIBLE (-6995 -180);
FORCEPROP 1 LAST COMMENT_BODY TRUE
R 1
J 0
(-6920 -405);
DISPLAY 0.872340 (-6920 -405);
PAINT GREEN (-6920 -405);
DISPLAY INVISIBLE (-6920 -405);
FORCEADD INTEL_CORP_BPAGE..1
(-450 -525);
FORCEPROP 1 LAST CDS_CON_LAST_MODIFIED Fri Jun 16 17:49:07 2017
J 0
(-1875 -200);
DISPLAY 0.659574 (-1875 -200);
PAINT GREEN (-1875 -200);
DISPLAY INVISIBLE (-1875 -200);
FORCEPROP 1 LAST CUSTOM_TXT_CDS <CURRENT_DESIGN_SHEET> OF <TOTAL_DESIGN_SHEETS>
J 0
(-950 -500);
PAINT ORANGE (-950 -500);
FORCEPROP 1 LAST CUSTOM_TXT_CDS <CON_LAST_MODIFIED>
J 0
(-4450 -425);
PAINT ORANGE (-4450 -425);
FORCEPROP 2 LAST CUSTOM_TXT_CDS <XR_PAGE_TITLE>
J 0
(-8340 4725);
DISPLAY 0.638298 (-8340 4725);
PAINT PINK (-8340 4725);
DISPLAY INVISIBLE (-8340 4725);
FORCEPROP 1 LAST SCH_TITLE AIRMAX 1X8 MID-PLANE CONNECTOR B
J 0
(-8400 -475);
DISPLAY 1.212766 (-8400 -475);
PAINT WHITE (-8400 -475);
FORCEPROP 1 LAST COMMENT_BODY TRUE
J 0
(-440 -515);
DISPLAY 0.297872 (-440 -515);
PAINT GREEN (-440 -515);
DISPLAY INVISIBLE (-440 -515);
FORCEPROP 2 LAST CDS_LIB mstr_symbols
J 0
(-450 -525);
DISPLAY 0.659574 (-450 -525);
PAINT ORANGE (-450 -525);
DISPLAY INVISIBLE (-450 -525);
FORCEPROP 2 LAST PAGE_BORDER TRUE
J 0
(-8340 4725);
DISPLAY 0.425532 (-8340 4725);
PAINT PINK (-8340 4725);
DISPLAY INVISIBLE (-8340 4725);
FORCEPROP 2 LAST CDS_XR_PAGE_TITLE CR-182 : @BASEBOARD_FAB2_LIB.BASEBOARD_FAB2(SCH_1):PAGE182
J 0
(-8340 4725);
DISPLAY 0.638298 (-8340 4725);
PAINT PINK (-8340 4725);
DISPLAY INVISIBLE (-8340 4725);
FORCEADD DNS..2
(-6995 220);
PAINT RED (-6995 220);
FORCEPROP 2 LAST CDS_LIB mstr_misc
J 0
(-6995 220);
PAINT ORANGE (-6995 220);
DISPLAY INVISIBLE (-6995 220);
FORCEPROP 1 LAST COMMENT_BODY TRUE
R 1
J 0
(-6920 -5);
DISPLAY 0.872340 (-6920 -5);
PAINT GREEN (-6920 -5);
DISPLAY INVISIBLE (-6920 -5);
FORCEADD DNS..2
(-6995 -30);
PAINT RED (-6995 -30);
FORCEPROP 2 LAST CDS_LIB mstr_misc
J 0
(-6995 -30);
PAINT ORANGE (-6995 -30);
DISPLAY INVISIBLE (-6995 -30);
FORCEPROP 1 LAST COMMENT_BODY TRUE
R 1
J 0
(-6920 -255);
DISPLAY 0.872340 (-6920 -255);
PAINT GREEN (-6920 -255);
DISPLAY INVISIBLE (-6920 -255);
FORCEADD DNS..2
(-6995 345);
PAINT RED (-6995 345);
FORCEPROP 2 LAST CDS_LIB mstr_misc
J 0
(-6995 345);
PAINT ORANGE (-6995 345);
DISPLAY INVISIBLE (-6995 345);
FORCEPROP 1 LAST COMMENT_BODY TRUE
R 1
J 0
(-6920 120);
DISPLAY 0.872340 (-6920 120);
PAINT GREEN (-6920 120);
DISPLAY INVISIBLE (-6920 120);
FORCEADD DNS..2
(-6995 95);
PAINT RED (-6995 95);
FORCEPROP 2 LAST CDS_LIB mstr_misc
J 0
(-6995 95);
PAINT ORANGE (-6995 95);
DISPLAY INVISIBLE (-6995 95);
FORCEPROP 1 LAST COMMENT_BODY TRUE
R 1
J 0
(-6920 -130);
DISPLAY 0.872340 (-6920 -130);
PAINT GREEN (-6920 -130);
DISPLAY INVISIBLE (-6920 -130);
WIRE 16 -1 (-5850 1075)(-5850 800);
WIRE 16 -1 (-5850 1225)(-5850 1075);
WIRE 16 -1 (-5850 1075)(-5625 1075);
WIRE 16 -1 (-5850 1225)(-5850 1375);
WIRE 16 -1 (-5850 1225)(-5625 1225);
WIRE 16 -1 (-5850 1375)(-5850 1525);
WIRE 16 -1 (-5625 1375)(-5850 1375);
WIRE 16 -1 (-5850 1525)(-5850 1625);
WIRE 16 -1 (-5625 1525)(-5850 1525);
WIRE 16 -1 (-5850 1625)(-5850 1775);
WIRE 16 -1 (-5625 1625)(-5850 1625);
WIRE 16 -1 (-5850 1925)(-5850 1775);
WIRE 16 -1 (-5850 1775)(-5625 1775);
WIRE 16 -1 (-5850 2125)(-5850 1925);
WIRE 16 -1 (-5850 1925)(-5625 1925);
WIRE 16 -1 (-5850 2275)(-5850 2125);
WIRE 16 -1 (-5625 2125)(-5850 2125);
WIRE 16 -1 (-5850 2425)(-5850 2275);
WIRE 16 -1 (-5850 2275)(-5625 2275);
WIRE 16 -1 (-5850 2575)(-5850 2425);
WIRE 16 -1 (-5850 2425)(-5625 2425);
WIRE 16 -1 (-5850 2675)(-5850 2575);
WIRE 16 -1 (-5850 2575)(-5625 2575);
WIRE 16 -1 (-5850 2825)(-5850 2675);
WIRE 16 -1 (-5850 2675)(-5625 2675);
WIRE 16 -1 (-5850 2975)(-5850 2825);
WIRE 16 -1 (-5850 2825)(-5625 2825);
WIRE 16 -1 (-5625 2975)(-5850 2975);
WIRE 16 -1 (-4200 750)(-4200 1075);
WIRE 16 -1 (-4200 1075)(-4200 1225);
WIRE 16 -1 (-4200 1075)(-4375 1075);
WIRE 16 -1 (-4200 1225)(-4200 1375);
WIRE 16 -1 (-4200 1225)(-4375 1225);
WIRE 16 -1 (-4200 1375)(-4200 1525);
WIRE 16 -1 (-4200 1375)(-4375 1375);
WIRE 16 -1 (-4200 1525)(-4200 1625);
WIRE 16 -1 (-4200 1525)(-4375 1525);
WIRE 16 -1 (-4200 1625)(-4200 1775);
WIRE 16 -1 (-4200 1625)(-4375 1625);
WIRE 16 -1 (-4200 1775)(-4200 1925);
WIRE 16 -1 (-4200 1775)(-4375 1775);
WIRE 16 -1 (-4200 1925)(-4200 2125);
WIRE 16 -1 (-4200 1925)(-4375 1925);
WIRE 16 -1 (-4200 2125)(-4200 2275);
WIRE 16 -1 (-4200 2125)(-4375 2125);
WIRE 16 -1 (-4200 2275)(-4200 2425);
WIRE 16 -1 (-4200 2275)(-4375 2275);
WIRE 16 -1 (-4200 2575)(-4200 2425);
WIRE 16 -1 (-4200 2425)(-4375 2425);
WIRE 16 -1 (-4200 2675)(-4200 2575);
WIRE 16 -1 (-4375 2575)(-4200 2575);
WIRE 16 -1 (-4200 2825)(-4200 2675);
WIRE 16 -1 (-4375 2675)(-4200 2675);
WIRE 16 -1 (-4200 2825)(-4200 2975);
WIRE 16 -1 (-4200 2825)(-4375 2825);
WIRE 16 -1 (-4200 2975)(-4375 2975);
WIRE 17 -1 (-1100 3050)(-1875 3050);
FORCEPROP 2 LAST SIG_NAME P3E_CPU1_PE3_MP_TXN<15:8>
J 0
(-1835 3060);
DISPLAY 0.617021 (-1835 3060);
PAINT ORANGE (-1835 3060);
WIRE 17 -1 (-1875 2400)(-1875 3050);
WIRE 17 -1 (-1875 2250)(-1875 2400);
WIRE 17 -1 (-1875 2050)(-1875 2250);
WIRE 17 -1 (-1875 1350)(-1875 1150);
WIRE 17 -1 (-1875 2050)(-1875 1900);
WIRE 17 -1 (-1875 1750)(-1875 1900);
WIRE 17 -1 (-1875 1500)(-1875 1350);
WIRE 17 -1 (-1875 1500)(-1875 1750);
WIRE 17 -1 (-6400 3275)(-7925 3275);
FORCEPROP 2 LAST SIG_NAME P3E_CPU1_PE3_MP_RXN<15:8>
J 0
(-7910 3285);
DISPLAY 0.617021 (-7910 3285);
PAINT ORANGE (-7910 3285);
WIRE 17 -1 (-6400 3275)(-6400 3100);
WIRE 17 -1 (-6400 3100)(-6400 2950);
WIRE 17 -1 (-6400 2750)(-6400 2950);
WIRE 17 -1 (-6400 2550)(-6400 2750);
WIRE 17 -1 (-6400 2550)(-6400 2400);
WIRE 17 -1 (-6400 2000)(-6400 1900);
WIRE 17 -1 (-6400 2400)(-6400 2200);
WIRE 17 -1 (-6400 2200)(-6400 2000);
WIRE 17 -1 (-6150 3400)(-7925 3400);
FORCEPROP 2 LAST SIG_NAME P3E_CPU1_PE3_MP_RXP<15:8>
J 0
(-7910 3410);
DISPLAY 0.617021 (-7910 3410);
PAINT ORANGE (-7910 3410);
WIRE 17 -1 (-6150 3400)(-6150 3050);
WIRE 17 -1 (-6150 3050)(-6150 2900);
WIRE 17 -1 (-6150 2800)(-6150 2900);
WIRE 17 -1 (-6150 2500)(-6150 2800);
WIRE 17 -1 (-6150 2500)(-6150 2350);
WIRE 17 -1 (-6150 2350)(-6150 2250);
WIRE 17 -1 (-6150 2250)(-6150 2050);
WIRE 17 -1 (-6150 2050)(-6150 1850);
WIRE 17 -1 (-1100 3150)(-2125 3150);
FORCEPROP 2 LAST SIG_NAME P3E_CPU1_PE3_MP_TXP<15:8>
J 0
(-1835 3160);
DISPLAY 0.617021 (-1835 3160);
PAINT ORANGE (-1835 3160);
WIRE 17 -1 (-2125 3150)(-2125 2350);
WIRE 17 -1 (-2125 2200)(-2125 2350);
WIRE 17 -1 (-2125 2000)(-2125 2200);
WIRE 17 -1 (-2125 2000)(-2125 1850);
WIRE 17 -1 (-2125 1700)(-2125 1850);
WIRE 17 -1 (-2125 1300)(-2125 1200);
WIRE 17 -1 (-2125 1450)(-2125 1700);
WIRE 17 -1 (-2125 1450)(-2125 1300);
WIRE 16 -1 (-4375 2725)(-3300 2725);
FORCEPROP 2 LAST SIG_NAME FM_XRC_READY_N
J 0
(-4025 2735);
DISPLAY 0.617021 (-4025 2735);
PAINT ORANGE (-4025 2735);
WIRE 16 -1 (-3275 3075)(-4375 3075);
FORCEPROP 0 LAST SIG_NAME TP_IOA5
J 0
(-4010 3085);
DISPLAY 0.617021 (-4010 3085);
PAINT ORANGE (-4010 3085);
FORCEPROP 2 LASTPROP $XRERR UNIQUE?
J 0
(-3245 3075);
DISPLAY 0.638298 (-3245 3075);
PAINT MONO (-3245 3075);
DISPLAY INVISIBLE (-3245 3075);
WIRE 16 -1 (-3275 3025)(-4375 3025);
FORCEPROP 2 LAST SIG_NAME IRQ_BOARD_BMC_ALERT_N
J 0
(-4010 3035);
DISPLAY 0.617021 (-4010 3035);
PAINT ORANGE (-4010 3035);
WIRE 3 682 (-4450 750)(-5550 750);
WIRE 3 682 (-5550 750)(-5550 3375);
WIRE 3 682 (-4450 3375)(-4450 750);
WIRE 3 682 (-4450 3375)(-5550 3375);
WIRE 16 -1 (-5625 3025)(-6050 3025);
WIRE 16 -1 (-4375 1825)(-3500 1825);
FORCEPROP 2 LAST SIG_NAME P3E_CPU1_PE3_MP_C_TXP<12>
J 0
(-4185 1835);
DISPLAY 0.617021 (-4185 1835);
PAINT ORANGE (-4185 1835);
FORCEPROP 2 LASTPROP $XRERR UNIQUE?
J 0
(-4425 1835);
DISPLAY 0.638298 (-4425 1835);
PAINT MONO (-4425 1835);
DISPLAY INVISIBLE (-4425 1835);
WIRE 16 -1 (-2225 1975)(-3300 1975);
WIRE 16 -1 (-5625 2725)(-6300 2725);
WIRE 16 -1 (-6900 100)(-6025 100);
FORCEPROP 2 LAST SIG_NAME FAN_TACH2_R
J 2
(-6000 110);
DISPLAY 0.617021 (-6000 110);
PAINT ORANGE (-6000 110);
WIRE 16 -1 (-6900 225)(-6025 225);
FORCEPROP 2 LAST SIG_NAME FAN_TACH3_R
J 2
(-6000 235);
DISPLAY 0.617021 (-6000 235);
PAINT ORANGE (-6000 235);
WIRE 16 -1 (-6900 350)(-6025 350);
FORCEPROP 2 LAST SIG_NAME FAN_TACH1_R
J 2
(-6000 360);
DISPLAY 0.617021 (-6000 360);
PAINT ORANGE (-6000 360);
WIRE 16 -1 (-5625 1125)(-7050 1125);
FORCEPROP 0 LAST SIG_NAME TP_IOI4
J 0
(-7010 1135);
DISPLAY 0.617021 (-7010 1135);
PAINT ORANGE (-7010 1135);
FORCEPROP 2 LASTPROP $XRERR UNIQUE?
J 0
(-7290 1125);
DISPLAY 0.638298 (-7290 1125);
PAINT MONO (-7290 1125);
DISPLAY INVISIBLE (-7290 1125);
WIRE 16 -1 (-7050 1275)(-5625 1275);
FORCEPROP 0 LAST SIG_NAME TP_IOF4
J 0
(-7010 1285);
DISPLAY 0.617021 (-7010 1285);
PAINT ORANGE (-7010 1285);
FORCEPROP 2 LASTPROP $XRERR UNIQUE?
J 0
(-7290 1275);
DISPLAY 0.638298 (-7290 1275);
PAINT MONO (-7290 1275);
DISPLAY INVISIBLE (-7290 1275);
WIRE 16 -1 (-5625 1425)(-7050 1425);
FORCEPROP 0 LAST SIG_NAME FM_BB_BMC_MP_GPIO
J 0
(-7035 1435);
DISPLAY 0.617021 (-7035 1435);
PAINT ORANGE (-7035 1435);
WIRE 16 -1 (-5625 1725)(-7050 1725);
FORCEPROP 0 LAST SIG_NAME TP_IOG3
J 0
(-6985 1735);
DISPLAY 0.617021 (-6985 1735);
PAINT ORANGE (-6985 1735);
FORCEPROP 2 LASTPROP $XRERR UNIQUE?
J 0
(-7290 1725);
DISPLAY 0.638298 (-7290 1725);
PAINT MONO (-7290 1725);
DISPLAY INVISIBLE (-7290 1725);
WIRE 16 -1 (-5625 2925)(-6300 2925);
WIRE 16 -1 (-5625 1675)(-7050 1675);
FORCEPROP 0 LAST SIG_NAME TP_IOH3
J 0
(-6985 1685);
DISPLAY 0.617021 (-6985 1685);
PAINT ORANGE (-6985 1685);
FORCEPROP 2 LASTPROP $XRERR UNIQUE?
J 0
(-7290 1675);
DISPLAY 0.638298 (-7290 1675);
PAINT MONO (-7290 1675);
DISPLAY INVISIBLE (-7290 1675);
WIRE 16 3135 (-8400 975)(-8400 -250);
WIRE 16 3135 (-8400 -250)(-5650 -250);
WIRE 16 3135 (-6150 975)(-8400 975);
WIRE 16 3135 (-6150 575)(-6150 975);
WIRE 16 3135 (-5650 -250)(-5650 575);
WIRE 16 3135 (-5650 575)(-6150 575);
WIRE 16 -1 (-5625 2875)(-6050 2875);
WIRE 16 -1 (-3275 2875)(-4375 2875);
FORCEPROP 2 LAST SIG_NAME SMB_LAN_STBY_LVC3_SCL
J 0
(-4025 2885);
DISPLAY 0.617021 (-4025 2885);
PAINT ORANGE (-4025 2885);
WIRE 16 -1 (-4375 2525)(-3300 2525);
FORCEPROP 2 LAST SIG_NAME SMB_PEHPCPU1_STBY_LVC3_SDA
J 0
(-3910 2535);
DISPLAY 0.617021 (-3910 2535);
PAINT ORANGE (-3910 2535);
WIRE 16 -1 (-2225 2325)(-3300 2325);
WIRE 16 -1 (-2825 1675)(-2225 1675);
WIRE 16 -1 (-3300 1725)(-1975 1725);
WIRE 16 -1 (-2825 2025)(-1975 2025);
WIRE 16 -1 (-4375 2025)(-3025 2025);
FORCEPROP 2 LAST SIG_NAME P3E_CPU1_PE3_MP_C_TXN<11>
J 0
(-4185 2035);
DISPLAY 0.617021 (-4185 2035);
PAINT ORANGE (-4185 2035);
FORCEPROP 2 LASTPROP $XRERR UNIQUE?
J 0
(-4425 2035);
DISPLAY 0.638298 (-4425 2035);
PAINT MONO (-4425 2035);
DISPLAY INVISIBLE (-4425 2035);
WIRE 16 -1 (-3300 2175)(-2225 2175);
WIRE 16 -1 (-4375 2175)(-3500 2175);
FORCEPROP 2 LAST SIG_NAME P3E_CPU1_PE3_MP_C_TXP<15>
J 0
(-4185 2185);
DISPLAY 0.617021 (-4185 2185);
PAINT ORANGE (-4185 2185);
FORCEPROP 2 LASTPROP $XRERR UNIQUE?
J 0
(-4425 2185);
DISPLAY 0.638298 (-4425 2185);
PAINT MONO (-4425 2185);
DISPLAY INVISIBLE (-4425 2185);
WIRE 16 -1 (-2825 2225)(-1975 2225);
WIRE 16 -1 (-2825 2375)(-1975 2375);
WIRE 16 -1 (-4375 2225)(-3025 2225);
FORCEPROP 2 LAST SIG_NAME P3E_CPU1_PE3_MP_C_TXN<15>
J 0
(-4185 2235);
DISPLAY 0.617021 (-4185 2235);
PAINT ORANGE (-4185 2235);
FORCEPROP 2 LASTPROP $XRERR UNIQUE?
J 0
(-4425 2235);
DISPLAY 0.638298 (-4425 2235);
PAINT MONO (-4425 2235);
DISPLAY INVISIBLE (-4425 2235);
WIRE 16 -1 (-3500 2325)(-4375 2325);
FORCEPROP 2 LAST SIG_NAME P3E_CPU1_PE3_MP_C_TXP<14>
J 0
(-4185 2335);
DISPLAY 0.617021 (-4185 2335);
PAINT ORANGE (-4185 2335);
FORCEPROP 2 LASTPROP $XRERR UNIQUE?
J 0
(-4425 2335);
DISPLAY 0.638298 (-4425 2335);
PAINT MONO (-4425 2335);
DISPLAY INVISIBLE (-4425 2335);
WIRE 16 -1 (-3300 1425)(-2225 1425);
WIRE 16 -1 (-2825 1325)(-1975 1325);
WIRE 16 -1 (-4375 2925)(-3275 2925);
FORCEPROP 2 LAST SIG_NAME SMB_LAN_STBY_LVC3_SDA
J 0
(-4025 2935);
DISPLAY 0.617021 (-4025 2935);
PAINT ORANGE (-4025 2935);
WIRE 16 -1 (-2825 1875)(-1975 1875);
WIRE 16 -1 (-3300 1825)(-2225 1825);
WIRE 16 -1 (-7825 225)(-7100 225);
FORCEPROP 2 LAST SIG_NAME SMB_LAN_STBY_LVC3_SDA
J 0
(-7850 235);
DISPLAY 0.617021 (-7850 235);
PAINT ORANGE (-7850 235);
WIRE 16 -1 (-7825 100)(-7100 100);
FORCEPROP 2 LAST SIG_NAME IRQ_BOARD_BMC_ALERT_N
J 0
(-7850 110);
DISPLAY 0.617021 (-7850 110);
PAINT ORANGE (-7850 110);
WIRE 16 -1 (-7825 -25)(-7100 -25);
FORCEPROP 2 LAST SIG_NAME FM_BMC_READY_N
J 0
(-7850 -15);
DISPLAY 0.617021 (-7850 -15);
PAINT ORANGE (-7850 -15);
WIRE 16 -1 (-7825 -175)(-7100 -175);
FORCEPROP 2 LAST SIG_NAME FM_XRC_READY_N
J 0
(-7850 -165);
DISPLAY 0.617021 (-7850 -165);
PAINT ORANGE (-7850 -165);
WIRE 16 -1 (-7825 350)(-7100 350);
FORCEPROP 2 LAST SIG_NAME SMB_LAN_STBY_LVC3_SCL
J 0
(-7850 360);
DISPLAY 0.617021 (-7850 360);
PAINT ORANGE (-7850 360);
WIRE 16 -1 (-6900 -25)(-6025 -25);
FORCEPROP 2 LAST SIG_NAME FAN_PWM_OUT_SYS0_R1
J 2
(-6000 -15);
DISPLAY 0.617021 (-6000 -15);
PAINT ORANGE (-6000 -15);
WIRE 16 -1 (-6900 -175)(-6025 -175);
FORCEPROP 2 LAST SIG_NAME FAN_TACH0_R
J 2
(-6000 -165);
DISPLAY 0.617021 (-6000 -165);
PAINT ORANGE (-6000 -165);
WIRE 16 -1 (-2825 1175)(-2225 1175);
WIRE 16 -1 (-3300 1275)(-2225 1275);
WIRE 16 -1 (-3300 1125)(-1975 1125);
WIRE 16 -1 (-4375 1325)(-3025 1325);
FORCEPROP 2 LAST SIG_NAME P3E_CPU1_PE3_MP_C_TXN<9>
J 0
(-4185 1335);
DISPLAY 0.617021 (-4185 1335);
PAINT ORANGE (-4185 1335);
FORCEPROP 2 LASTPROP $XRERR UNIQUE?
J 0
(-4425 1335);
DISPLAY 0.638298 (-4425 1335);
PAINT MONO (-4425 1335);
DISPLAY INVISIBLE (-4425 1335);
WIRE 16 -1 (-4375 1425)(-3500 1425);
FORCEPROP 2 LAST SIG_NAME P3E_CPU1_PE3_MP_C_TXP<8>
J 0
(-4185 1435);
DISPLAY 0.617021 (-4185 1435);
PAINT ORANGE (-4185 1435);
FORCEPROP 2 LASTPROP $XRERR UNIQUE?
J 0
(-4425 1435);
DISPLAY 0.638298 (-4425 1435);
PAINT MONO (-4425 1435);
DISPLAY INVISIBLE (-4425 1435);
WIRE 16 -1 (-3025 1475)(-4375 1475);
FORCEPROP 2 LAST SIG_NAME P3E_CPU1_PE3_MP_C_TXN<8>
J 0
(-4185 1485);
DISPLAY 0.617021 (-4185 1485);
PAINT ORANGE (-4185 1485);
FORCEPROP 2 LASTPROP $XRERR UNIQUE?
J 0
(-4425 1485);
DISPLAY 0.638298 (-4425 1485);
PAINT MONO (-4425 1485);
DISPLAY INVISIBLE (-4425 1485);
WIRE 16 -1 (-4375 1675)(-3025 1675);
FORCEPROP 2 LAST SIG_NAME P3E_CPU1_PE3_MP_C_TXP<13>
J 0
(-4185 1685);
DISPLAY 0.617021 (-4185 1685);
PAINT ORANGE (-4185 1685);
FORCEPROP 2 LASTPROP $XRERR UNIQUE?
J 0
(-4425 1685);
DISPLAY 0.638298 (-4425 1685);
PAINT MONO (-4425 1685);
DISPLAY INVISIBLE (-4425 1685);
WIRE 16 -1 (-4375 1725)(-3500 1725);
FORCEPROP 2 LAST SIG_NAME P3E_CPU1_PE3_MP_C_TXN<13>
J 0
(-4185 1735);
DISPLAY 0.617021 (-4185 1735);
PAINT ORANGE (-4185 1735);
FORCEPROP 2 LASTPROP $XRERR UNIQUE?
J 0
(-4425 1735);
DISPLAY 0.638298 (-4425 1735);
PAINT MONO (-4425 1735);
DISPLAY INVISIBLE (-4425 1735);
WIRE 16 -1 (-4375 1875)(-3025 1875);
FORCEPROP 2 LAST SIG_NAME P3E_CPU1_PE3_MP_C_TXN<12>
J 0
(-4185 1885);
DISPLAY 0.617021 (-4185 1885);
PAINT ORANGE (-4185 1885);
FORCEPROP 2 LASTPROP $XRERR UNIQUE?
J 0
(-4425 1885);
DISPLAY 0.638298 (-4425 1885);
PAINT MONO (-4425 1885);
DISPLAY INVISIBLE (-4425 1885);
WIRE 16 -1 (-4375 2375)(-3025 2375);
FORCEPROP 2 LAST SIG_NAME P3E_CPU1_PE3_MP_C_TXN<14>
J 0
(-4185 2385);
DISPLAY 0.617021 (-4185 2385);
PAINT ORANGE (-4185 2385);
FORCEPROP 2 LASTPROP $XRERR UNIQUE?
J 0
(-4425 2385);
DISPLAY 0.638298 (-4425 2385);
PAINT MONO (-4425 2385);
DISPLAY INVISIBLE (-4425 2385);
WIRE 16 -1 (-5625 1475)(-7050 1475);
FORCEPROP 0 LAST SIG_NAME TP_FM_WAKE_N
J 0
(-7035 1485);
DISPLAY 0.617021 (-7035 1485);
PAINT ORANGE (-7035 1485);
FORCEPROP 2 LASTPROP $XRERR UNIQUE?
J 0
(-7290 1475);
DISPLAY 0.638298 (-7290 1475);
PAINT MONO (-7290 1475);
DISPLAY INVISIBLE (-7290 1475);
WIRE 16 -1 (-5625 1175)(-7050 1175);
FORCEPROP 0 LAST SIG_NAME TP_IOH4
J 0
(-7010 1185);
DISPLAY 0.617021 (-7010 1185);
PAINT ORANGE (-7010 1185);
FORCEPROP 2 LASTPROP $XRERR UNIQUE?
J 0
(-7290 1175);
DISPLAY 0.638298 (-7290 1175);
PAINT MONO (-7290 1175);
DISPLAY INVISIBLE (-7290 1175);
WIRE 16 -1 (-7050 1325)(-5625 1325);
FORCEPROP 0 LAST SIG_NAME TP_IOE4
J 0
(-7010 1335);
DISPLAY 0.617021 (-7010 1335);
PAINT ORANGE (-7010 1335);
FORCEPROP 2 LASTPROP $XRERR UNIQUE?
J 0
(-7290 1325);
DISPLAY 0.638298 (-7290 1325);
PAINT MONO (-7290 1325);
DISPLAY INVISIBLE (-7290 1325);
WIRE 16 -1 (-5625 3075)(-6300 3075);
WIRE 16 -1 (-5625 2775)(-6050 2775);
WIRE 16 -1 (-5625 2475)(-6050 2475);
WIRE 16 -1 (-5625 2325)(-6050 2325);
WIRE 16 -1 (-5625 2225)(-6050 2225);
WIRE 16 -1 (-5625 2375)(-6300 2375);
WIRE 16 -1 (-5625 2525)(-6300 2525);
WIRE 16 -1 (-5625 2175)(-6300 2175);
WIRE 16 -1 (-5625 2025)(-6050 2025);
WIRE 16 -1 (-5625 1825)(-6050 1825);
WIRE 16 -1 (-5625 1875)(-6300 1875);
WIRE 16 -1 (-5625 1975)(-6300 1975);
WIRE 16 -1 (-4375 1125)(-3500 1125);
FORCEPROP 2 LAST SIG_NAME P3E_CPU1_PE3_MP_C_TXN<10>
J 0
(-4185 1135);
DISPLAY 0.617021 (-4185 1135);
PAINT ORANGE (-4185 1135);
FORCEPROP 2 LASTPROP $XRERR UNIQUE?
J 0
(-4425 1135);
DISPLAY 0.638298 (-4425 1135);
PAINT MONO (-4425 1135);
DISPLAY INVISIBLE (-4425 1135);
WIRE 16 -1 (-4375 1175)(-3025 1175);
FORCEPROP 2 LAST SIG_NAME P3E_CPU1_PE3_MP_C_TXP<10>
J 0
(-4185 1185);
DISPLAY 0.617021 (-4185 1185);
PAINT ORANGE (-4185 1185);
FORCEPROP 2 LASTPROP $XRERR UNIQUE?
J 0
(-4425 1185);
DISPLAY 0.638298 (-4425 1185);
PAINT MONO (-4425 1185);
DISPLAY INVISIBLE (-4425 1185);
WIRE 16 -1 (-4375 1275)(-3500 1275);
FORCEPROP 2 LAST SIG_NAME P3E_CPU1_PE3_MP_C_TXP<9>
J 0
(-4185 1285);
DISPLAY 0.617021 (-4185 1285);
PAINT ORANGE (-4185 1285);
FORCEPROP 2 LASTPROP $XRERR UNIQUE?
J 0
(-4425 1285);
DISPLAY 0.638298 (-4425 1285);
PAINT MONO (-4425 1285);
DISPLAY INVISIBLE (-4425 1285);
WIRE 16 -1 (-3500 1975)(-4375 1975);
FORCEPROP 2 LAST SIG_NAME P3E_CPU1_PE3_MP_C_TXP<11>
J 0
(-4185 1985);
DISPLAY 0.617021 (-4185 1985);
PAINT ORANGE (-4185 1985);
FORCEPROP 2 LASTPROP $XRERR UNIQUE?
J 0
(-4425 1985);
DISPLAY 0.638298 (-4425 1985);
PAINT MONO (-4425 1985);
DISPLAY INVISIBLE (-4425 1985);
WIRE 16 -1 (-4375 2475)(-3300 2475);
FORCEPROP 2 LAST SIG_NAME SMB_PEHPCPU1_STBY_LVC3_SCL
J 0
(-3910 2485);
DISPLAY 0.617021 (-3910 2485);
PAINT ORANGE (-3910 2485);
WIRE 16 -1 (-3300 2775)(-4375 2775);
FORCEPROP 2 LAST SIG_NAME FM_XRC_PRESENT_N
J 0
(-4025 2785);
DISPLAY 0.617021 (-4025 2785);
PAINT ORANGE (-4025 2785);
WIRE 16 -1 (-1975 1475)(-2825 1475);
DOT 1 (-4200 1925);
DOT 1 (-4200 2675);
DOT 1 (-4200 2425);
DOT 1 (-4200 2275);
DOT 1 (-4200 2125);
DOT 1 (-4200 1775);
DOT 1 (-4200 1625);
DOT 1 (-4200 1525);
DOT 1 (-4200 1375);
DOT 1 (-4200 1075);
DOT 1 (-4200 2825);
DOT 1 (-4200 2575);
DOT 1 (-5850 2825);
DOT 1 (-5850 2675);
DOT 1 (-5850 2575);
DOT 1 (-5850 2425);
DOT 1 (-5850 2275);
DOT 1 (-5850 2125);
DOT 1 (-5850 1925);
DOT 1 (-5850 1775);
DOT 1 (-5850 1625);
DOT 1 (-5850 1375);
DOT 1 (-5850 1525);
DOT 1 (-5850 1075);
DOT 1 (-5850 1225);
DOT 1 (-4200 1225);
FORCENOTE
PLACE CAPS NEAR MID-PLANE CONNECTOR
(-3725 875) 0;
DISPLAY LEFT (-3725 875);
DISPLAY 1.021277 (-3725 875);
PAINT PURPLE (-3725 875);
FORCENOTE
ROOM: IO_SLOT
(-8319 -336) 0;
DISPLAY LEFT (-8319 -336);
DISPLAY 1.021277 (-8319 -336);
PAINT PURPLE (-8319 -336);
FORCENOTE
CAD NOTE:
(-3725 950) 0;
DISPLAY LEFT (-3725 950);
DISPLAY 1.021277 (-3725 950);
PAINT PURPLE (-3725 950);
FORCENOTE
TP FAB1 CHANGE SYMBOL TO ZZ.82092.07601 0310
(-5550 3400) 0;
DISPLAY LEFT (-5550 3400);
DISPLAY 1.021277 (-5550 3400);
PAINT RED (-5550 3400);
QUIT
